P  UNITS CUST 0
C   
C   vSure IPC 356 OUTPUT.  
C
C   FTP Site : valor.com
C   WEB Site : http://www.valor.com 
C
P   NNAME00000     ADM1276_LATCH_B                                          
P   NNAME00001     TEMP_ALM#_REVERSE_R                                      
P   NNAME00002     I2C_C_SCL_CONN_R                                         
P   NNAME00003     I2C_C_SDA_CONN_R                                         
P   NNAME00004     PWM_OUT_FAN1_NET                                         
P   NNAME00005     P12VL_2490_EN_1                                          
P   NNAME00006     P12VL_2490_EN_2                                          
P   NNAME00007     PEER_TRAY_PRESENT_LOWER                                  
P   NNAME00008     FCB_HW_REVISION                                          
P   NNAME00009     SD_LATCH_RELEASE_L                                       
P   NNAME00010     SELF_TRAY_PRESENT_LOWER                                  
P   NNAME00011     PWM_OUT_FAN2_NET                                         
P   NNAME00012     PWM_OUT_FAN3_NET                                         
P   NNAME00013     PWM_OUT_FAN4_NET                                         
P   NNAME00014     PWM_OUT_FAN5_NET                                         
P   NNAME00015     PWM_OUT_FAN6_NET                                         
P   NNAME00016     P12VU_2490_EN_1                                          
P   NNAME00017     P12VU_2490_EN_2                                          
P   NNAME00018     PEER_TRAY_PRESENT_UPPER                                  
P   NNAME00019     SD_LATCH_RELEASE_U                                       
P   NNAME00020     SELF_TRAY_PRESENT_UPPER                                  
P   NNAME00021     TEMP_ALM#_REVERSE                                        
P   NNAME00022     OTP_RETRY_DIODE                                          
P   NNAME00023     LED_DR_LED0_BLUE                                         
P   NNAME00024     LED_DR_LED1_BLUE                                         
P   NNAME00025     LED_DR_LED2_BLUE                                         
P   NNAME00026     LED_DR_LED3_BLUE                                         
P   NNAME00027     LED_DR_LED4_BLUE                                         
P   NNAME00028     LED_DR_LED5_BLUE                                         
P   NNAME00029     ADM1276_GATE_RC                                          
P   NNAME00030     P12V_SENSE_TRACE                                         
P   NNAME00031     P12VU_2490_SENSE                                         
P   NNAME00032     P12VL_2490_SENSE                                         
P   NNAME00033     P12VU_2490_TIMER                                         
P   NNAME00034     P12VL_2490_TIMER                                         
P   NNAME00035     P12VU_2490_VREF                                          
P   NNAME00036     P12VL_2490_VREF                                          
P   NNAME00037     ADM1276_GATE_RSV                                         
P   NNAME00038     ADM1276_GATE_DRV1                                        
P   NNAME00039     P12VU_2490_GATE_DRV_2                                    
P   NNAME00040     P12VL_2490_GATE_DRV_2                                    
P   NNAME00041     ADM1276_GATE_DRV0                                        
P   NNAME00042     ADM1276_GATE_DRV2                                        
P   NNAME00043     ADM1276_GATE_DRV3                                        
P   NNAME00044     P12VU_2490_GATE_DRV                                      
P   NNAME00045     P12VL_2490_GATE_DRV                                      
P   NNAME00046     ADM1276_GATE_DRV                                         
P   NNAME00047     P12VL_2490_GATE                                          
P   NNAME00048     P12VU_2490_GATE                                          
P   NNAME00049     P12VU_2490_PROG                                          
P   NNAME00050     P12VL_2490_PROG                                          
P   NNAME00051     I2C_C_SDA_ADM1276                                        
P   NNAME00052     I2C_C_SCL_ADM1276                                        
P   NNAME00053     I2C_C_SDA_NCT7904                                        
P   NNAME00054     NCT7904_CASEOPEN                                         
P   NNAME00055     I2C_C_SDA_LEDDRV                                         
P   NNAME00056     I2C_C_SCL_LEDDRV                                         
P   NNAME00057     NCT7904_VSEN_P12V_AUX                                    
P   NNAME00058     PWM_BUFFER_IN_FAN1_FAN2                                  
P   NNAME00059     PWM_BUFFER_IN_FAN3_FAN4                                  
P   NNAME00060     PWM_BUFFER_IN_FAN5_FAN6                                  
P   NNAME00061     I2C_C_SCL_NCT7904                                        
P   NNAME00062     I2C_C_SCL_EEPROM                                         
P   NNAME00063     I2C_C_SDA_EEPROM                                         
P   NNAME00064     SEB_PEER_1A_1B_HB_OUT                                    
P   NNAME00065     SEB_PEER_2A_2B_HB_OUT                                    
P   NNAME00066     LED_DR_LED6_RESERVE                                      
P   NNAME00067     LED_DR_LED7_RESERVE                                      
P   NNAME00068     NCT7904_THERMTRIP                                        
P   NNAME00069     NCT7904_PROCHOT                                          
327$NONE$                       D0040PA01X+017118Y+073230               S0      
327$NONE$                       D0040PA01X+016862Y+073230               S0      
317$NONE$                       D0040PA00X+008071Y+032941               S0      
317$NONE$                       D0040PA00X+008071Y+030941               S0      
317$NONE$                       D0040PA00X+008071Y+013941               S0      
317$NONE$                       D0040PA00X+008071Y+011941               S0      
317$NONE$                       D0040PA00X+011894Y+177882               S0      
317$NONE$                       D0040PA00X+012894Y+177882               S0      
317$NONE$                       D0040PA00X+013894Y+177882               S0      
317$NONE$                       D0040PA00X+014961Y+032941               S0      
317$NONE$                       D0040PA00X+014961Y+030941               S0      
317$NONE$                       D0040PA00X+014961Y+013941               S0      
317$NONE$                       D0040PA00X+014961Y+011941               S0      
327$NONE$                       D0040PA01X+015000Y+006450               S0      
327$NONE$                       D0040PA01X+015250Y+190600               S0      
327$NONE$                       D0040PA01X-018044Y+194726               S0      
327$NONE$                       D0040PA01X-018114Y+002001               S0      
327$NONE$                       D0040PA01X+060170Y+002125               S0      
327$NONE$                       D0040PA01X+060240Y+194850               S0      
317$NONE$                       D0040PA00X-022244Y+194882               S0      
317$NONE$                       D0040PA00X-022244Y+001969               S0      
317$NONE$                       D0040PA00X+064370Y+194882               S0      
317$NONE$                       D0040PA00X+064370Y+001969               S0      
317$NONE$           VIA        MD0040PA01X+004724Y+006811               S0      
317$NONE$           VIA        MD0040PA04X+004724Y+006811               S0      
317$NONE$           VIA        MD0040PA01X+004724Y+050134               S0      
317$NONE$           VIA        MD0040PA04X+004724Y+050134               S0      
317$NONE$           VIA        MD0040PA01X+004724Y+076118               S0      
317$NONE$           VIA        MD0040PA04X+004724Y+076118               S0      
317$NONE$           VIA        MD0040PA01X+004724Y+120732               S0      
317$NONE$           VIA        MD0040PA04X+004724Y+120732               S0      
317$NONE$           VIA        MD0040PA01X+004724Y+146717               S0      
317$NONE$           VIA        MD0040PA04X+004724Y+146717               S0      
317$NONE$           VIA        MD0040PA01X+004724Y+190039               S0      
317$NONE$           VIA        MD0040PA04X+004724Y+190039               S0      
317$NONE$           VIA        MD0040PA01X+002992Y+002480               S0      
317$NONE$           VIA        MD0040PA04X+002992Y+002480               S0      
317$NONE$           VIA        MD0040PA01X+002992Y+011142               S0      
317$NONE$           VIA        MD0040PA04X+002992Y+011142               S0      
317$NONE$           VIA        MD0040PA01X+002992Y+045803               S0      
317$NONE$           VIA        MD0040PA04X+002992Y+045803               S0      
317$NONE$           VIA        MD0040PA01X+002992Y+054465               S0      
317$NONE$           VIA        MD0040PA04X+002992Y+054465               S0      
317$NONE$           VIA        MD0040PA01X+002992Y+071787               S0      
317$NONE$           VIA        MD0040PA04X+002992Y+071787               S0      
317$NONE$           VIA        MD0040PA01X+002992Y+080449               S0      
317$NONE$           VIA        MD0040PA04X+002992Y+080449               S0      
317$NONE$           VIA        MD0040PA01X+003000Y+116400               S0      
317$NONE$           VIA        MD0040PA04X+003000Y+116400               S0      
317$NONE$           VIA        MD0040PA01X+002992Y+125063               S0      
317$NONE$           VIA        MD0040PA04X+002992Y+125063               S0      
317$NONE$           VIA        MD0040PA01X+002992Y+142386               S0      
317$NONE$           VIA        MD0040PA04X+002992Y+142386               S0      
317$NONE$           VIA        MD0040PA01X+002992Y+151047               S0      
317$NONE$           VIA        MD0040PA04X+002992Y+151047               S0      
317$NONE$           VIA        MD0040PA01X+002992Y+185709               S0      
317$NONE$           VIA        MD0040PA04X+002992Y+185709               S0      
317$NONE$           VIA        MD0040PA01X+002992Y+194370               S0      
317$NONE$           VIA        MD0040PA04X+002992Y+194370               S0      
317NCT7904_3VDD                 D0040PA01X+015854Y+060968               S0      
317NCT7904_3VDD                 D0040PA01X+014636Y+061132               S0      
327NCT7904_3VDD                 D0040PA01X+015227Y+060897               S0      
327NCT7904_3VDD                 D0040PA01X+013624Y+062244               S0      
317NCT7904_3VDD     VIA        MD0040PA01X+016310Y+060472               S0      
317GND                          D0040PA01X+014070Y+069550               S0      
327GND                          D0040PA01X+007200Y+067461               S0      
317GND                          D0040PA01X+007570Y+071550               S0      
317GND                          D0040PA01X+005690Y+017130               S0      
317GND                          D0040PA01X+013354Y+066203               S0      
317GND                          D0040PA01X+012990Y+099250               S0      
317GND                          D0040PA01X+008740Y+057770               S0      
317GND                          D0040PA01X+009630Y+055770               S0      
317GND                          D0040PA01X+015350Y+057000               S0      
317GND                          D0040PA00X+001591Y+052134               S0      
317GND                          D0040PA01X+003720Y+025690               S0      
327GND                          D0040PA01X+015838Y+071010               S0      
327GND                          D0040PA01X+017118Y+071010               S0      
327GND                          D0040PA01X+016350Y+073230               S0      
327GND                          D0040PA01X+016094Y+073230               S0      
317GND                          D0040PA00X+017913Y+116142               S0      
327GND                          D0040PA01X+001954Y+171487               S0      
327GND                          D0040PA01X+018520Y+035670               S0      
317GND                          D0040PA01X+007720Y+070590               S0      
317GND                          D0040PA01X+009130Y+067100               S0      
317GND                          D0040PA01X+008750Y+087845               S0      
327GND                          D0040PA01X+008800Y+097630               S0      
317GND                          D0040PA01X+007100Y+098660               S0      
317GND                          D0040PA01X+012980Y+142830               S0      
317GND                          D0040PA01X+010150Y+099080               S0      
317GND                          D0040PA01X+014430Y+111130               S0      
317GND                          D0040PA01X+006720Y+071100               S0      
317GND                          D0040PA01X+012936Y+069217               S0      
327GND                          D0040PA01X+001910Y+066700               S0      
327GND                          D0040PA01X+009600Y+093100               S0      
327GND                          D0040PA01X+002763Y+164905               S0      
317GND                          D0040PA01X+012253Y+095234               S0      
327GND                          D0040PA01X+007890Y+149870               S0      
317GND                          D0040PA01X+001990Y+176960               S0      
317GND                          D0040PA01X+003350Y+108360               S0      
317GND                          D0040PA01X+005810Y+103440               S0      
317GND                          D0040PA01X+018790Y+164800               S0      
317GND                          D0040PA01X+014040Y+057240               S0      
327GND                          D0040PA01X+003236Y+168050               S0      
317GND                          D0040PA01X+015050Y+070280               S0      
327GND                          D0040PA01X+008146Y+056105               S0      
317GND                          D0040PA00X+001591Y+008811               S0      
317GND                          D0040PA01X+009170Y+006150               S0      
317GND                          D0040PA01X+009130Y+144650               S0      
327GND                          D0040PA01X+019130Y+160650               S0      
317GND                          D0040PA01X+009230Y+087845               S0      
327GND                          D0040PA01X+011520Y+055830               S0      
317GND                          D0040PA00X+002756Y+181102               S0      
317GND                          D0040PA01X+016010Y+055330               S0      
327GND                          D0040PA01X+012164Y+096300               S0      
317GND                          D0040PA01X+010120Y+147450               S0      
317GND                          D0040PA01X+014530Y+058220               S0      
317GND                          D0040PA01X+016330Y+069650               S0      
327GND                          D0040PA01X+003187Y+109696               S0      
317GND                          D0040PA01X+014900Y+111135               S0      
327GND                          D0040PA01X+014580Y+115130               S0      
317GND                          D0040PA01X+013150Y+094440               S0      
317GND                          D0040PA01X+004750Y+023890               S0      
317GND                          D0040PA01X+010530Y+105840               S0      
327GND                          D0040PA01X+018540Y+037690               S0      
327GND                          D0040PA01X+002290Y+039780               S0      
317GND                          D0040PA01X+009130Y+057320               S0      
317GND                          D0040PA01X+011753Y+095234               S0      
317GND                          D0040PA01X+002410Y+069090               S0      
327GND                          D0040PA01X+017010Y+061520               S0      
327GND                          D0040PA01X+014938Y+068225               S0      
317GND                          D0040PA01X+018790Y+165270               S0      
317GND                          D0040PA01X+011480Y+100130               S0      
327GND                          D0040PA01X+003660Y+155150               S0      
317GND                          D0040PA01X+005180Y+176030               S0      
317GND                          D0040PA01X+007700Y+073080               S0      
317GND                          D0040PA00X+008071Y+023441               S0      
317GND                          D0040PA00X+008071Y+021441               S0      
317GND                          D0040PA00X+009071Y+024441               S0      
317GND                          D0040PA00X+009071Y+022441               S0      
317GND                          D0040PA00X+009071Y+020441               S0      
317GND                          D0040PA00X+008071Y+019189               S0      
317GND                          D0040PA00X+009071Y+019189               S0      
317GND                          D0040PA00X+010071Y+019189               S0      
317GND                          D0040PA00X+011071Y+019189               S0      
317GND                          D0040PA00X+008071Y+018189               S0      
317GND                          D0040PA00X+009071Y+018189               S0      
317GND                          D0040PA00X+010071Y+018189               S0      
317GND                          D0040PA00X+011071Y+018189               S0      
317GND                          D0040PA00X+008071Y+017189               S0      
317GND                          D0040PA00X+009071Y+017189               S0      
317GND                          D0040PA00X+010071Y+017189               S0      
317GND                          D0040PA00X+011071Y+017189               S0      
317GND                          D0040PA00X+008071Y+016189               S0      
317GND                          D0040PA00X+009071Y+016189               S0      
317GND                          D0040PA00X+010071Y+016189               S0      
317GND                          D0040PA00X+011071Y+016189               S0      
327GND                          D0040PA01X+002290Y+041830               S0      
317GND                          D0040PA01X+007840Y+058760               S0      
327GND                          D0040PA01X+018830Y+164100               S0      
317GND                          D0040PA01X+012926Y+068367               S0      
317GND                          D0040PA01X+006380Y+066230               S0      
317GND                          D0040PA01X+006030Y+017930               S0      
327GND                          D0040PA01X+015578Y+140145               S0      
317GND                          D0040PA01X+014390Y+145840               S0      
317GND                          D0040PA01X+005380Y+100950               S0      
327GND                          D0040PA01X+014527Y+055925               S0      
327GND                          D0040PA01X+015526Y+095950               S0      
317GND                          D0040PA00X+001591Y+148717               S0      
327GND                          D0040PA01X+012430Y+190830               S0      
327GND                          D0040PA01X+008020Y+147750               S0      
317GND                          D0040PA01X+002590Y+172170               S0      
317GND                          D0040PA01X+008920Y+007150               S0      
327GND                          D0040PA01X+015980Y+064584               S0      
317GND                          D0040PA01X+005060Y+025280               S0      
317GND                          D0040PA01X+005690Y+023660               S0      
317GND                          D0040PA01X+006760Y+114450               S0      
327GND                          D0040PA01X+010600Y+138750               S0      
317GND                          D0040PA01X+014636Y+060772               S0      
317GND                          D0040PA01X+002670Y+178780               S0      
317GND                          D0040PA01X+009450Y+097670               S0      
317GND                          D0040PA01X+012080Y+058520               S0      
327GND                          D0040PA01X+010590Y+039850               S0      
317GND                          D0040PA01X+007854Y+069464               S0      
327GND                          D0040PA01X+008950Y+146930               S0      
317GND                          D0040PA01X+005280Y+176980               S0      
327GND                          D0040PA01X+006380Y+098660               S0      
317GND                          D0040PA01X+007220Y+071100               S0      
327GND                          D0040PA01X+017210Y+054150               S0      
317GND                          D0040PA01X+006320Y+114200               S0      
327GND                          D0040PA01X+009917Y+148064               S0      
317GND                          D0040PA01X+013600Y+094440               S0      
327GND                          D0040PA01X+010590Y+041900               S0      
317GND                          D0040PA01X+006380Y+065760               S0      
317GND                          D0040PA00X+001772Y+133858               S0      
317GND                          D0040PA01X+007520Y+073790               S0      
327GND                          D0040PA01X+014700Y+073200               S0      
327GND                          D0040PA01X+005175Y+068544               S0      
317GND                          D0040PA01X+009970Y+053780               S0      
317GND                          D0040PA01X+003920Y+034380               S0      
327GND                          D0040PA01X+011617Y+084630               S0      
327GND                          D0040PA01X+012470Y+139230               S0      
317GND                          D0040PA01X+004960Y+057350               S0      
317GND                          D0040PA01X+007054Y+069391               S0      
317GND                          D0040PA01X+013080Y+097580               S0      
317GND                          D0040PA01X+012926Y+068806               S0      
317GND                          D0040PA01X+007210Y+099980               S0      
327GND                          D0040PA01X+011380Y+139714               S0      
327GND                          D0040PA01X+010640Y+140226               S0      
317GND                          D0040PA01X+016540Y+142680               S0      
317GND                          D0040PA01X+005780Y+022100               S0      
317GND                          D0040PA01X+012490Y+058520               S0      
327GND                          D0040PA01X+001972Y+026255               S0      
317GND                          D0040PA01X+016142Y+177343               S0      
317GND                          D0040PA01X+009120Y+144280               S0      
327GND                          D0040PA01X+007360Y+079840               S0      
317GND                          D0040PA01X+014950Y+058220               S0      
317GND                          D0040PA01X+006030Y+015530               S0      
317GND                          D0040PA01X+012907Y+067309               S0      
317GND                          D0040PA01X+011580Y+076410               S0      
317GND                          D0040PA01X+004880Y+091640               S0      
317GND                          D0040PA00X+001591Y+078118               S0      
317GND                          D0040PA01X+003500Y+058490               S0      
327GND                          D0040PA01X+012660Y+145712               S0      
327GND                          D0040PA01X+011700Y+145200               S0      
317GND                          D0040PA01X+016270Y+062670               S0      
317GND                          D0040PA01X+008340Y+114300               S0      
317GND                          D0040PA01X+010350Y+059390               S0      
317GND                          D0040PA01X+009120Y+143490               S0      
327GND                          D0040PA01X+018500Y+155160               S0      
317GND                          D0040PA01X+015980Y+054930               S0      
317GND                          D0040PA00X+002756Y+062992               S0      
317GND                          D0040PA01X+007180Y+005295               S0      
317GND                          D0040PA01X+012347Y+067309               S0      
327GND                          D0040PA01X+006370Y+109060               S0      
317GND                          D0040PA01X+008920Y+145550               S0      
317GND                          D0040PA00X+017913Y+057087               S0      
317GND                          D0040PA01X+010390Y+047660               S0      
327GND                          D0040PA01X+003625Y+068544               S0      
317GND                          D0040PA01X+005960Y+102060               S0      
317GND                          D0040PA01X+006270Y+025420               S0      
317GND                          D0040PA01X+009550Y+146420               S0      
317GND                          D0040PA01X+014745Y+187870               S0      
317GND                          D0040PA01X+002890Y+069090               S0      
327GND                          D0040PA01X+011074Y+036180               S0      
317GND                          D0040PA00X+014961Y+023441               S0      
317GND                          D0040PA00X+014961Y+021441               S0      
317GND                          D0040PA00X+015961Y+024441               S0      
317GND                          D0040PA00X+015961Y+022441               S0      
317GND                          D0040PA00X+015961Y+020441               S0      
317GND                          D0040PA00X+014961Y+019189               S0      
317GND                          D0040PA00X+015961Y+019189               S0      
317GND                          D0040PA00X+016961Y+019189               S0      
317GND                          D0040PA00X+017961Y+019189               S0      
317GND                          D0040PA00X+014961Y+018189               S0      
317GND                          D0040PA00X+015961Y+018189               S0      
317GND                          D0040PA00X+016961Y+018189               S0      
317GND                          D0040PA00X+017961Y+018189               S0      
317GND                          D0040PA00X+014961Y+017189               S0      
317GND                          D0040PA00X+015961Y+017189               S0      
317GND                          D0040PA00X+016961Y+017189               S0      
317GND                          D0040PA00X+017961Y+017189               S0      
317GND                          D0040PA00X+014961Y+016189               S0      
317GND                          D0040PA00X+015961Y+016189               S0      
317GND                          D0040PA00X+016961Y+016189               S0      
317GND                          D0040PA00X+017961Y+016189               S0      
317GND                          D0040PA01X+016460Y+061210               S0      
327GND                          D0040PA01X+017324Y+143747               S0      
317GND                          D0040PA00X+001591Y+192039               S0      
317GND                          D0040PA01X+014670Y+047670               S0      
317GND                          D0040PA01X+012888Y+140195               S0      
327GND                          D0040PA01X+015227Y+060137               S0      
327GND                          D0040PA01X+011729Y+071050               S0      
317GND                          D0040PA01X+014800Y+139400               S0      
317GND                          D0040PA01X+006030Y+016330               S0      
327GND                          D0040PA01X+018757Y+150770               S0      
317GND                          D0040PA01X+006090Y+057300               S0      
327GND                          D0040PA01X+008944Y+064263               S0      
317GND                          D0040PA01X+012970Y+143200               S0      
327GND                          D0040PA01X+005094Y+090987               S0      
317GND                          D0040PA01X+007410Y+057620               S0      
327GND                          D0040PA01X+018490Y+153150               S0      
317GND                          D0040PA01X+005220Y+023890               S0      
317GND                          D0040PA00X+017913Y+007874               S0      
317GND                          D0040PA01X+011130Y+038010               S0      
317GND                          D0040PA01X+013668Y+055717               S0      
317GND                          D0040PA01X+005740Y+020790               S0      
317GND                          D0040PA01X+007140Y+006815               S0      
327GND                          D0040PA01X+014644Y+142227               S0      
317GND                          D0040PA01X+011253Y+095234               S0      
317GND                          D0040PA01X+009560Y+142370               S0      
317GND                          D0040PA01X+009120Y+143150               S0      
317GND                          D0040PA01X+014740Y+188370               S0      
317GND                          D0040PA00X+001591Y+122732               S0      
327GND                          D0040PA01X+009937Y+036190               S0      
317GND                          D0040PA01X+013470Y+140060               S0      
327GND                          D0040PA01X+010326Y+068492               S0      
317GND                          D0040PA01X+007860Y+057450               S0      
317GND                          D0040PA01X+010530Y+105370               S0      
317GND                          D0040PA01X+010220Y+055330               S0      
327GND                          D0040PA01X+018530Y+041840               S0      
317GND                          D0040PA01X+007700Y+113450               S0      
317GND                          D0040PA01X+018047Y+063137               S0      
317GND                          D0040PA01X+009350Y+147920               S0      
317GND                          D0040PA01X+010970Y+142160               S0      
317GND                          D0040PA01X+014050Y+094440               S0      
327GND                          D0040PA01X+003268Y+030535               S0      
327GND                          D0040PA01X+013790Y+008850               S0      
317GND                          D0040PA01X+007390Y+055880               S0      
317GND                          D0040PA01X+011580Y+076910               S0      
317GND                          D0040PA01X+013350Y+147120               S0      
317GND                          D0040PA01X+017420Y+053640               S0      
317GND                          D0040PA01X+006564Y+069391               S0      
317GND                          D0040PA01X+015470Y+146250               S0      
317GND                          D0040PA01X+010150Y+098600               S0      
327GND                          D0040PA01X+018530Y+039790               S0      
317GND                          D0040PA01X+001860Y+164020               S0      
327GND                          D0040PA01X+015400Y+138750               S0      
317GND                          D0040PA01X+003440Y+029430               S0      
317GND                          D0040PA00X+017913Y+188976               S0      
317GND                          D0040PA00X+017894Y+132874               S0      
317GND                          D0040PA00X+002756Y+015748               S0      
317GND                          D0040PA00X+016142Y+182303               S0      
317GND                          D0040PA00X+016142Y+174784               S0      
317GND              VIA        MD0040PA04X+010400Y+073400               S0      
317GND              VIA        MD0040PA04X+012100Y+113300               S0      
317GND              VIA        MD0040PA04X+012100Y+114750               S0      
317GND              VIA        MD0040PA04X+012700Y+012900               S0      
317GND              VIA        MD0040PA04X+013170Y+057110               S0      
317GND              VIA        MD0040PA04X+014450Y+187700               S0      
317GND              VIA        MD0040PA04X+015400Y+035550               S0      
317GND              VIA        MD0040PA04X+016650Y+064000               S0      
317GND              VIA        MD0040PA04X+017100Y+140750               S0      
317GND              VIA        MD0040PA04X+017350Y+074050               S0      
317GND              VIA        MD0040PA04X+003100Y+128050               S0      
317GND              VIA        MD0040PA04X+003700Y+171400               S0      
317GND              VIA        MD0040PA04X+004200Y+065550               S0      
317GND              VIA        MD0040PA04X+005750Y+105050               S0      
317GND              VIA        MD0040PA04X+005850Y+110450               S0      
317GND              VIA        MD0040PA04X+007500Y+188200               S0      
317GND              VIA        MD0040PA04X+008800Y+103450               S0      
317GND              VIA        MD0040PA04X+009100Y+127250               S0      
317GND              VIA        MD0040PA04X+009150Y+109300               S0      
317GND              VIA        MD0040PA04X+009300Y+188450               S0      
317GND              VIA        MD0040PA04X+009750Y+190100               S0      
317GND              VIA        MD0040PA01X+012850Y+107680               S0      
317GND              VIA        MD0040PA01X+016050Y+091650               S0      
317GND              VIA        MD0040PA01X+016200Y+102700               S0      
317GND              VIA        MD0040PA01X+017850Y+126850               S0      
317GND              VIA        MD0040PA01X+001860Y+024910               S0      
317GND              VIA        MD0040PA01X+018600Y+113300               S0      
317GND              VIA        MD0040PA01X+018900Y+143200               S0      
317GND              VIA        MD0040PA01X+003300Y+157500               S0      
317GND              VIA        MD0040PA01X+004310Y+086610               S0      
317GND              VIA        MD0040PA01X+004390Y+013720               S0      
317GND              VIA        MD0040PA00X+010086Y+140226               S0      
317GND              VIA        MD0040PA00X+010100Y+058300               S0      
317GND              VIA        MD0040PA00X+010270Y+054100               S0      
317GND              VIA        MD0040PA00X+010400Y+104950               S0      
317GND              VIA        MD0040PA00X+010400Y+106250               S0      
317GND              VIA        MD0040PA00X+010460Y+192340               S0      
317GND              VIA        MD0040PA00X+010500Y+118100               S0      
317GND              VIA        MD0040PA00X+010550Y+070250               S0      
317GND              VIA        MD0040PA00X+010600Y+070900               S0      
317GND              VIA        MD0040PA00X+010630Y+055320               S0      
317GND              VIA        MD0040PA00X+010810Y+047765               S0      
317GND              VIA        MD0040PA00X+010890Y+054130               S0      
317GND              VIA        MD0040PA00X+011100Y+139400               S0      
317GND              VIA        MD0040PA00X+011350Y+072100               S0      
317GND              VIA        MD0040PA00X+011350Y+072900               S0      
317GND              VIA        MD0040PA00X+011350Y+073600               S0      
317GND              VIA        MD0040PA00X+011350Y+074700               S0      
317GND              VIA        MD0040PA00X+011350Y+075600               S0      
317GND              VIA        MD0040PA00X+011450Y+070050               S0      
317GND              VIA        MD0040PA00X+011870Y+084070               S0      
317GND              VIA        MD0040PA00X+011950Y+073950               S0      
317GND              VIA        MD0040PA00X+011950Y+074650               S0      
317GND              VIA        MD0040PA00X+011950Y+075750               S0      
317GND              VIA        MD0040PA00X+011980Y+056830               S0      
317GND              VIA        MD0040PA00X+012100Y+058150               S0      
317GND              VIA        MD0040PA00X+012250Y+070050               S0      
317GND              VIA        MD0040PA00X+012420Y+056840               S0      
317GND              VIA        MD0040PA00X+012490Y+058200               S0      
317GND              VIA        MD0040PA00X+012500Y+139850               S0      
317GND              VIA        MD0040PA00X+012510Y+140250               S0      
317GND              VIA        MD0040PA00X+012540Y+098360               S0      
317GND              VIA        MD0040PA00X+012540Y+099200               S0      
317GND              VIA        MD0040PA00X+012890Y+192330               S0      
317GND              VIA        MD0040PA00X+013000Y+070050               S0      
317GND              VIA        MD0040PA00X+013000Y+074600               S0      
317GND              VIA        MD0040PA00X+013000Y+075300               S0      
317GND              VIA        MD0040PA00X+013000Y+076400               S0      
317GND              VIA        MD0040PA00X+013350Y+190650               S0      
317GND              VIA        MD0040PA00X+013350Y+057550               S0      
317GND              VIA        MD0040PA00X+013350Y+058200               S0      
317GND              VIA        MD0040PA00X+013460Y+058670               S0      
317GND              VIA        MD0040PA00X+013460Y+066560               S0      
317GND              VIA        MD0040PA00X+013500Y+056150               S0      
317GND              VIA        MD0040PA00X+013700Y+058990               S0      
317GND              VIA        MD0040PA00X+001400Y+047600               S0      
317GND              VIA        MD0040PA00X+014200Y+047850               S0      
317GND              VIA        MD0040PA00X+014210Y+058140               S0      
317GND              VIA        MD0040PA00X+014240Y+192380               S0      
317GND              VIA        MD0040PA00X+014250Y+055000               S0      
317GND              VIA        MD0040PA00X+014580Y+059440               S0      
317GND              VIA        MD0040PA00X+014600Y+072600               S0      
317GND              VIA        MD0040PA00X+014600Y+073800               S0      
317GND              VIA        MD0040PA00X+014600Y+075500               S0      
317GND              VIA        MD0040PA00X+014600Y+076550               S0      
317GND              VIA        MD0040PA00X+014600Y+078250               S0      
317GND              VIA        MD0040PA00X+014600Y+079650               S0      
317GND              VIA        MD0040PA00X+014600Y+082400               S0      
317GND              VIA        MD0040PA00X+014630Y+191370               S0      
317GND              VIA        MD0040PA00X+014650Y+139710               S0      
317GND              VIA        MD0040PA00X+014650Y+081200               S0      
317GND              VIA        MD0040PA00X+014700Y+052990               S0      
317GND              VIA        MD0040PA00X+014700Y+070300               S0      
317GND              VIA        MD0040PA00X+014900Y+067700               S0      
317GND              VIA        MD0040PA00X+014950Y+005200               S0      
317GND              VIA        MD0040PA00X+014980Y+100870               S0      
317GND              VIA        MD0040PA00X+015150Y+103050               S0      
317GND              VIA        MD0040PA00X+015190Y+189140               S0      
317GND              VIA        MD0040PA00X+015250Y+188310               S0      
317GND              VIA        MD0040PA00X+015350Y+103350               S0      
317GND              VIA        MD0040PA00X+015550Y+103000               S0      
317GND              VIA        MD0040PA00X+015590Y+139710               S0      
317GND              VIA        MD0040PA00X+015630Y+055210               S0      
317GND              VIA        MD0040PA00X+015750Y+066450               S0      
317GND              VIA        MD0040PA00X+015790Y+192310               S0      
317GND              VIA        MD0040PA00X+015950Y+106200               S0      
317GND              VIA        MD0040PA00X+016100Y+067400               S0      
317GND              VIA        MD0040PA00X+016150Y+074750               S0      
317GND              VIA        MD0040PA00X+016150Y+075900               S0      
317GND              VIA        MD0040PA00X+016150Y+076800               S0      
317GND              VIA        MD0040PA00X+016150Y+077800               S0      
317GND              VIA        MD0040PA00X+016160Y+073980               S0      
317GND              VIA        MD0040PA00X+016200Y+081750               S0      
317GND              VIA        MD0040PA00X+016210Y+191200               S0      
317GND              VIA        MD0040PA00X+016300Y+104250               S0      
317GND              VIA        MD0040PA00X+016310Y+097860               S0      
317GND              VIA        MD0040PA00X+016320Y+098520               S0      
317GND              VIA        MD0040PA00X+016543Y+069237               S0      
317GND              VIA        MD0040PA00X+016590Y+071730               S0      
317GND              VIA        MD0040PA00X+016600Y+075150               S0      
317GND              VIA        MD0040PA00X+016600Y+076000               S0      
317GND              VIA        MD0040PA00X+016650Y+077550               S0      
317GND              VIA        MD0040PA00X+016800Y+083000               S0      
317GND              VIA        MD0040PA00X+016900Y+142675               S0      
317GND              VIA        MD0040PA00X+017000Y+192050               S0      
317GND              VIA        MD0040PA00X+017000Y+074550               S0      
317GND              VIA        MD0040PA00X+017400Y+083450               S0      
317GND              VIA        MD0040PA00X+017510Y+071000               S0      
317GND              VIA        MD0040PA00X+017670Y+192390               S0      
317GND              VIA        MD0040PA00X+017770Y+191280               S0      
317GND              VIA        MD0040PA00X+017900Y+100500               S0      
317GND              VIA        MD0040PA00X+017950Y+088400               S0      
317GND              VIA        MD0040PA00X+017980Y+094140               S0      
317GND              VIA        MD0040PA00X+017990Y+090090               S0      
317GND              VIA        MD0040PA00X+017990Y+092570               S0      
317GND              VIA        MD0040PA00X+018000Y+085600               S0      
317GND              VIA        MD0040PA00X+018000Y+087250               S0      
317GND              VIA        MD0040PA00X+018000Y+091250               S0      
317GND              VIA        MD0040PA00X+018000Y+096040               S0      
317GND              VIA        MD0040PA00X+018050Y+097320               S0      
317GND              VIA        MD0040PA00X+018450Y+192050               S0      
317GND              VIA        MD0040PA00X+019250Y+164800               S0      
317GND              VIA        MD0040PA00X+019250Y+165300               S0      
317GND              VIA        MD0040PA00X+019265Y+164150               S0      
317GND              VIA        MD0040PA00X+019450Y+150550               S0      
317GND              VIA        MD0040PA00X+019450Y+151000               S0      
317GND              VIA        MD0040PA00X+001954Y+171052               S0      
317GND              VIA        MD0040PA00X+019500Y+111200               S0      
317GND              VIA        MD0040PA00X+019650Y+157200               S0      
317GND              VIA        MD0040PA00X+019650Y+160650               S0      
317GND              VIA        MD0040PA00X+020050Y+187650               S0      
317GND              VIA        MD0040PA00X+020110Y+190880               S0      
317GND              VIA        MD0040PA00X+020120Y+189050               S0      
317GND              VIA        MD0040PA00X+020139Y+106700               S0      
317GND              VIA        MD0040PA00X+020139Y+142550               S0      
317GND              VIA        MD0040PA00X+020139Y+079700               S0      
317GND              VIA        MD0040PA00X+020150Y+101900               S0      
317GND              VIA        MD0040PA00X+020150Y+108250               S0      
317GND              VIA        MD0040PA00X+020150Y+114700               S0      
317GND              VIA        MD0040PA00X+020150Y+130650               S0      
317GND              VIA        MD0040PA00X+020150Y+135000               S0      
317GND              VIA        MD0040PA00X+020150Y+135950               S0      
317GND              VIA        MD0040PA00X+020150Y+141300               S0      
317GND              VIA        MD0040PA00X+020150Y+016500               S0      
317GND              VIA        MD0040PA00X+020150Y+069150               S0      
317GND              VIA        MD0040PA00X+020150Y+072650               S0      
317GND              VIA        MD0040PA00X+020150Y+077700               S0      
317GND              VIA        MD0040PA00X+020150Y+093150               S0      
317GND              VIA        MD0040PA00X+020150Y+099100               S0      
317GND              VIA        MD0040PA00X+020170Y+138830               S0      
317GND              VIA        MD0040PA00X+020200Y+103700               S0      
317GND              VIA        MD0040PA00X+020200Y+105200               S0      
317GND              VIA        MD0040PA00X+020200Y+121200               S0      
317GND              VIA        MD0040PA00X+020200Y+124600               S0      
317GND              VIA        MD0040PA00X+020200Y+085950               S0      
317GND              VIA        MD0040PA00X+020200Y+087500               S0      
317GND              VIA        MD0040PA00X+020200Y+089000               S0      
317GND              VIA        MD0040PA00X+020200Y+091800               S0      
317GND              VIA        MD0040PA00X+020221Y+146200               S0      
317GND              VIA        MD0040PA00X+020221Y+063850               S0      
317GND              VIA        MD0040PA00X+020221Y+090350               S0      
317GND              VIA        MD0040PA00X+020240Y+144400               S0      
317GND              VIA        MD0040PA00X+020250Y+100600               S0      
317GND              VIA        MD0040PA00X+020250Y+117900               S0      
317GND              VIA        MD0040PA00X+020250Y+128000               S0      
317GND              VIA        MD0040PA00X+020250Y+066600               S0      
317GND              VIA        MD0040PA00X+020250Y+075550               S0      
317GND              VIA        MD0040PA00X+020250Y+082200               S0      
317GND              VIA        MD0040PA00X+020250Y+084650               S0      
317GND              VIA        MD0040PA00X+020250Y+094550               S0      
317GND              VIA        MD0040PA00X+020250Y+096200               S0      
317GND              VIA        MD0040PA00X+020250Y+097750               S0      
317GND              VIA        MD0040PA00X+002200Y+178780               S0      
317GND              VIA        MD0040PA00X+002310Y+034240               S0      
317GND              VIA        MD0040PA00X+002340Y+035350               S0      
317GND              VIA        MD0040PA00X+002670Y+152980               S0      
317GND              VIA        MD0040PA00X+002740Y+189940               S0      
317GND              VIA        MD0040PA00X+002800Y+159680               S0      
317GND              VIA        MD0040PA00X+002880Y+053370               S0      
317GND              VIA        MD0040PA00X+002910Y+172155               S0      
317GND              VIA        MD0040PA00X+002950Y+034350               S0      
317GND              VIA        MD0040PA00X+002950Y+041050               S0      
317GND              VIA        MD0040PA00X+002950Y+058650               S0      
317GND              VIA        MD0040PA00X+003140Y+164820               S0      
317GND              VIA        MD0040PA00X+003260Y+029050               S0      
317GND              VIA        MD0040PA00X+003268Y+029950               S0      
317GND              VIA        MD0040PA00X+003320Y+046890               S0      
317GND              VIA        MD0040PA00X+003400Y+169150               S0      
317GND              VIA        MD0040PA00X+003400Y+044800               S0      
317GND              VIA        MD0040PA00X+003420Y+028480               S0      
317GND              VIA        MD0040PA00X+003550Y+167050               S0      
317GND              VIA        MD0040PA00X+003600Y+026039               S0      
317GND              VIA        MD0040PA00X+003640Y+152340               S0      
317GND              VIA        MD0040PA00X+003840Y+159670               S0      
317GND              VIA        MD0040PA00X+003870Y+189380               S0      
317GND              VIA        MD0040PA00X+003930Y+018110               S0      
317GND              VIA        MD0040PA00X+003940Y+138130               S0      
317GND              VIA        MD0040PA00X+003980Y+068140               S0      
317GND              VIA        MD0040PA00X+004030Y+170390               S0      
317GND              VIA        MD0040PA00X+004150Y+169200               S0      
317GND              VIA        MD0040PA00X+004150Y+188950               S0      
317GND              VIA        MD0040PA00X+004250Y+167300               S0      
317GND              VIA        MD0040PA00X+004250Y+026020               S0      
317GND              VIA        MD0040PA00X+004270Y+160600               S0      
317GND              VIA        MD0040PA00X+004330Y+164660               S0      
317GND              VIA        MD0040PA00X+004350Y+162070               S0      
317GND              VIA        MD0040PA00X+004360Y+166830               S0      
317GND              VIA        MD0040PA00X+004410Y+168520               S0      
317GND              VIA        MD0040PA00X+004450Y+138050               S0      
317GND              VIA        MD0040PA00X+004450Y+167800               S0      
317GND              VIA        MD0040PA00X+000459Y+071400               S0      
317GND              VIA        MD0040PA00X+000459Y+074900               S0      
317GND              VIA        MD0040PA00X+004500Y+142800               S0      
317GND              VIA        MD0040PA00X+004550Y+140000               S0      
317GND              VIA        MD0040PA00X+004550Y+169000               S0      
317GND              VIA        MD0040PA00X+004700Y+188620               S0      
317GND              VIA        MD0040PA00X+004970Y+056890               S0      
317GND              VIA        MD0040PA00X+000500Y+135500               S0      
317GND              VIA        MD0040PA00X+000509Y+057450               S0      
317GND              VIA        MD0040PA00X+005080Y+026640               S0      
317GND              VIA        MD0040PA00X+005100Y+052950               S0      
317GND              VIA        MD0040PA00X+005170Y+023480               S0      
317GND              VIA        MD0040PA00X+005250Y+175600               S0      
317GND              VIA        MD0040PA00X+005250Y+024850               S0      
317GND              VIA        MD0040PA00X+005250Y+068250               S0      
317GND              VIA        MD0040PA00X+000530Y+052890               S0      
317GND              VIA        MD0040PA00X+000530Y+054880               S0      
317GND              VIA        MD0040PA00X+005300Y+017150               S0      
317GND              VIA        MD0040PA00X+005300Y+069510               S0      
317GND              VIA        MD0040PA00X+005380Y+100620               S0      
317GND              VIA        MD0040PA00X+005420Y+020785               S0      
317GND              VIA        MD0040PA00X+005420Y+022070               S0      
317GND              VIA        MD0040PA00X+005430Y+091550               S0      
317GND              VIA        MD0040PA00X+005450Y+103550               S0      
317GND              VIA        MD0040PA00X+005460Y+057340               S0      
317GND              VIA        MD0040PA00X+005590Y+188150               S0      
317GND              VIA        MD0040PA00X+005600Y+102150               S0      
317GND              VIA        MD0040PA00X+005750Y+089030               S0      
317GND              VIA        MD0040PA00X+005750Y+098430               S0      
317GND              VIA        MD0040PA00X+005750Y+098780               S0      
317GND              VIA        MD0040PA00X+005790Y+189980               S0      
317GND              VIA        MD0040PA00X+005894Y+025629               S0      
317GND              VIA        MD0040PA00X+005950Y+088160               S0      
317GND              VIA        MD0040PA00X+005960Y+012580               S0      
317GND              VIA        MD0040PA00X+006030Y+189230               S0      
317GND              VIA        MD0040PA00X+006035Y+015195               S0      
317GND              VIA        MD0040PA00X+006200Y+187700               S0      
317GND              VIA        MD0040PA00X+006350Y+017930               S0      
317GND              VIA        MD0040PA00X+006400Y+066660               S0      
317GND              VIA        MD0040PA00X+006450Y+109900               S0      
317GND              VIA        MD0040PA00X+006500Y+016630               S0      
317GND              VIA        MD0040PA00X+006500Y+056150               S0      
317GND              VIA        MD0040PA00X+006530Y+188660               S0      
317GND              VIA        MD0040PA00X+006600Y+055050               S0      
317GND              VIA        MD0040PA00X+006620Y+065350               S0      
317GND              VIA        MD0040PA00X+007035Y+055885               S0      
317GND              VIA        MD0040PA00X+007080Y+099050               S0      
317GND              VIA        MD0040PA00X+007145Y+053219               S0      
317GND              VIA        MD0040PA00X+007150Y+073550               S0      
317GND              VIA        MD0040PA00X+007240Y+052830               S0      
317GND              VIA        MD0040PA00X+007350Y+073200               S0      
317GND              VIA        MD0040PA00X+007400Y+006050               S0      
317GND              VIA        MD0040PA00X+007500Y+006750               S0      
317GND              VIA        MD0040PA00X+007840Y+058370               S0      
317GND              VIA        MD0040PA00X+007849Y+069783               S0      
317GND              VIA        MD0040PA00X+007900Y+006550               S0      
317GND              VIA        MD0040PA00X+007990Y+192300               S0      
317GND              VIA        MD0040PA00X+008000Y+147200               S0      
317GND              VIA        MD0040PA00X+008200Y+065200               S0      
317GND              VIA        MD0040PA00X+008300Y+097980               S0      
317GND              VIA        MD0040PA00X+008320Y+145550               S0      
317GND              VIA        MD0040PA00X+008350Y+097280               S0      
317GND              VIA        MD0040PA00X+008350Y+097630               S0      
317GND              VIA        MD0040PA00X+008420Y+064387               S0      
317GND              VIA        MD0040PA00X+008450Y+005650               S0      
317GND              VIA        MD0040PA00X+008700Y+059100               S0      
317GND              VIA        MD0040PA00X+008700Y+064800               S0      
317GND              VIA        MD0040PA00X+008800Y+058650               S0      
317GND              VIA        MD0040PA00X+008850Y+070000               S0      
317GND              VIA        MD0040PA00X+008900Y+059500               S0      
317GND              VIA        MD0040PA00X+009110Y+192280               S0      
317GND              VIA        MD0040PA00X+009130Y+057700               S0      
317GND              VIA        MD0040PA00X+009220Y+055380               S0      
317GND              VIA        MD0040PA00X+009250Y+007300               S0      
317GND              VIA        MD0040PA00X+009300Y+069850               S0      
317GND              VIA        MD0040PA00X+009400Y+097180               S0      
317GND              VIA        MD0040PA00X+009600Y+058800               S0      
317GND              VIA        MD0040PA00X+009730Y+099080               S0      
317GND              VIA        MD0040PA00X+009800Y+069850               S0      
317GND              VIA        MD0040PA00X+009800Y+070300               S0      
317GND              VIA        MD0040PA00X+009800Y+070800               S0      
317GND              VIA        MD0040PA00X+001000Y+081150               S0      
317GND              VIA        MD0040PA00X+010050Y+138450               S0      
317GND              VIA        MD0040PA00X+010050Y+138900               S0      
317GND              VIA        MD0040PA00X+010130Y+039010               S0      
317GND              VIA        MD0040PA00X+010150Y+040650               S0      
317GND              VIA        MD0040PA00X+010250Y+042650               S0      
317GND              VIA        MD0040PA00X+010250Y+089350               S0      
317GND              VIA        MD0040PA00X+010291Y+067397               S0      
317GND              VIA        MD0040PA00X+010300Y+124490               S0      
317GND              VIA        MD0040PA00X+010310Y+058760               S0      
317GND              VIA        MD0040PA00X+010350Y+102850               S0      
317GND              VIA        MD0040PA00X+010350Y+104200               S0      
317GND              VIA        MD0040PA00X+010350Y+107350               S0      
317GND              VIA        MD0040PA00X+010350Y+122900               S0      
317GND              VIA        MD0040PA00X+010350Y+069550               S0      
317GND              VIA        MD0040PA00X+010350Y+090950               S0      
317GND              VIA        MD0040PA00X+010370Y+147030               S0      
317GND              VIA        MD0040PA00X+010400Y+101400               S0      
317GND              VIA        MD0040PA00X+010450Y+109500               S0      
317GND              VIA        MD0040PA00X+010450Y+120800               S0      
317GND              VIA        MD0040PA00X+010450Y+121950               S0      
317GND              VIA        MD0040PA00X+010500Y+119600               S0      
317GND              VIA        MD0040PA00X+010500Y+012500               S0      
317GND              VIA        MD0040PA00X+010500Y+014300               S0      
317GND              VIA        MD0040PA00X+010500Y+015500               S0      
317GND              VIA        MD0040PA00X+010500Y+004500               S0      
317GND              VIA        MD0040PA00X+010500Y+005500               S0      
317GND              VIA        MD0040PA00X+010500Y+095800               S0      
317GND              VIA        MD0040PA00X+010550Y+039000               S0      
317GND              VIA        MD0040PA00X+010550Y+040650               S0      
317GND              VIA        MD0040PA00X+010550Y+099600               S0      
317GND              VIA        MD0040PA00X+010650Y+100850               S0      
317GND              VIA        MD0040PA00X+010700Y+042650               S0      
317GND              VIA        MD0040PA00X+010700Y+090300               S0      
317GND              VIA        MD0040PA00X+010700Y+091800               S0      
317GND              VIA        MD0040PA00X+010711Y+067400               S0      
317GND              VIA        MD0040PA00X+010850Y+069550               S0      
317GND              VIA        MD0040PA00X+010850Y+096400               S0      
317GND              VIA        MD0040PA00X+010850Y+097100               S0      
317GND              VIA        MD0040PA00X+010900Y+108350               S0      
317GND              VIA        MD0040PA00X+011000Y+141800               S0      
317GND              VIA        MD0040PA00X+011000Y+094950               S0      
317GND              VIA        MD0040PA00X+011050Y+104150               S0      
317GND              VIA        MD0040PA00X+011050Y+105100               S0      
317GND              VIA        MD0040PA00X+011050Y+106450               S0      
317GND              VIA        MD0040PA00X+011050Y+111200               S0      
317GND              VIA        MD0040PA00X+011050Y+040650               S0      
317GND              VIA        MD0040PA00X+011120Y+042640               S0      
317GND              VIA        MD0040PA00X+011150Y+102000               S0      
317GND              VIA        MD0040PA00X+011150Y+103000               S0      
317GND              VIA        MD0040PA00X+011150Y+039000               S0      
317GND              VIA        MD0040PA00X+011200Y+124450               S0      
317GND              VIA        MD0040PA00X+011200Y+125050               S0      
317GND              VIA        MD0040PA00X+011350Y+079250               S0      
317GND              VIA        MD0040PA00X+011350Y+090950               S0      
317GND              VIA        MD0040PA00X+011380Y+128790               S0      
317GND              VIA        MD0040PA00X+011380Y+133190               S0      
317GND              VIA        MD0040PA00X+011400Y+127400               S0      
317GND              VIA        MD0040PA00X+011400Y+131800               S0      
317GND              VIA        MD0040PA00X+011400Y+137600               S0      
317GND              VIA        MD0040PA00X+011400Y+080000               S0      
317GND              VIA        MD0040PA00X+011450Y+129650               S0      
317GND              VIA        MD0040PA00X+011450Y+137050               S0      
317GND              VIA        MD0040PA00X+011450Y+080550               S0      
317GND              VIA        MD0040PA00X+011480Y+100500               S0      
317GND              VIA        MD0040PA00X+011500Y+110850               S0      
317GND              VIA        MD0040PA00X+011500Y+004500               S0      
317GND              VIA        MD0040PA00X+011500Y+070450               S0      
317GND              VIA        MD0040PA00X+011500Y+077320               S0      
317GND              VIA        MD0040PA00X+011500Y+081300               S0      
317GND              VIA        MD0040PA00X+011500Y+092000               S0      
317GND              VIA        MD0040PA00X+011520Y+078420               S0      
317GND              VIA        MD0040PA00X+011550Y+093000               S0      
317GND              VIA        MD0040PA00X+011580Y+136390               S0      
317GND              VIA        MD0040PA00X+011600Y+135000               S0      
317GND              VIA        MD0040PA00X+011605Y+090325               S0      
317GND              VIA        MD0040PA00X+011650Y+103550               S0      
317GND              VIA        MD0040PA00X+011650Y+104900               S0      
317GND              VIA        MD0040PA00X+011650Y+106250               S0      
317GND              VIA        MD0040PA00X+011650Y+107600               S0      
317GND              VIA        MD0040PA00X+011650Y+075200               S0      
317GND              VIA        MD0040PA00X+011700Y+100850               S0      
317GND              VIA        MD0040PA00X+011700Y+053000               S0      
317GND              VIA        MD0040PA00X+011750Y+102350               S0      
317GND              VIA        MD0040PA00X+011750Y+125100               S0      
317GND              VIA        MD0040PA00X+011750Y+089300               S0      
317GND              VIA        MD0040PA00X+011753Y+094884               S0      
317GND              VIA        MD0040PA00X+011800Y+012450               S0      
317GND              VIA        MD0040PA00X+011800Y+014250               S0      
317GND              VIA        MD0040PA00X+011800Y+015450               S0      
317GND              VIA        MD0040PA00X+011800Y+192200               S0      
317GND              VIA        MD0040PA00X+011800Y+005450               S0      
317GND              VIA        MD0040PA00X+011850Y+116600               S0      
317GND              VIA        MD0040PA00X+011900Y+010950               S0      
317GND              VIA        MD0040PA00X+011900Y+126900               S0      
317GND              VIA        MD0040PA00X+011900Y+067330               S0      
317GND              VIA        MD0040PA00X+011900Y+097500               S0      
317GND              VIA        MD0040PA00X+011930Y+119140               S0      
317GND              VIA        MD0040PA00X+011930Y+121940               S0      
317GND              VIA        MD0040PA00X+011930Y+124540               S0      
317GND              VIA        MD0040PA00X+011950Y+117750               S0      
317GND              VIA        MD0040PA00X+011950Y+120550               S0      
317GND              VIA        MD0040PA00X+011950Y+123150               S0      
317GND              VIA        MD0040PA00X+001200Y+127400               S0      
317GND              VIA        MD0040PA00X+001200Y+129400               S0      
317GND              VIA        MD0040PA00X+012000Y+110200               S0      
317GND              VIA        MD0040PA00X+012000Y+110800               S0      
317GND              VIA        MD0040PA00X+012000Y+071750               S0      
317GND              VIA        MD0040PA00X+012000Y+091600               S0      
317GND              VIA        MD0040PA00X+012050Y+073250               S0      
317GND              VIA        MD0040PA00X+012100Y+076790               S0      
317GND              VIA        MD0040PA00X+012100Y+077600               S0      
317GND              VIA        MD0040PA00X+012150Y+078350               S0      
317GND              VIA        MD0040PA00X+012250Y+079250               S0      
317GND              VIA        MD0040PA00X+012300Y+080000               S0      
317GND              VIA        MD0040PA00X+012300Y+080850               S0      
317GND              VIA        MD0040PA00X+012350Y+081600               S0      
317GND              VIA        MD0040PA00X+012350Y+084250               S0      
317GND              VIA        MD0040PA00X+012380Y+128390               S0      
317GND              VIA        MD0040PA00X+012380Y+131190               S0      
317GND              VIA        MD0040PA00X+012380Y+133790               S0      
317GND              VIA        MD0040PA00X+012380Y+136590               S0      
317GND              VIA        MD0040PA00X+012400Y+127000               S0      
317GND              VIA        MD0040PA00X+012400Y+129800               S0      
317GND              VIA        MD0040PA00X+012400Y+132400               S0      
317GND              VIA        MD0040PA00X+012400Y+135200               S0      
317GND              VIA        MD0040PA00X+012400Y+137650               S0      
317GND              VIA        MD0040PA00X+012400Y+007450               S0      
317GND              VIA        MD0040PA00X+012400Y+090900               S0      
317GND              VIA        MD0040PA00X+012400Y+097150               S0      
317GND              VIA        MD0040PA00X+012450Y+082510               S0      
317GND              VIA        MD0040PA00X+012450Y+085800               S0      
317GND              VIA        MD0040PA00X+012450Y+087650               S0      
317GND              VIA        MD0040PA00X+012462Y+095924               S0      
317GND              VIA        MD0040PA00X+012480Y+069660               S0      
317GND              VIA        MD0040PA00X+001250Y+178250               S0      
317GND              VIA        MD0040PA00X+001250Y+195900               S0      
317GND              VIA        MD0040PA00X+001250Y+019750               S0      
317GND              VIA        MD0040PA00X+001250Y+026650               S0      
317GND              VIA        MD0040PA00X+012500Y+004500               S0      
317GND              VIA        MD0040PA00X+012500Y+073400               S0      
317GND              VIA        MD0040PA00X+012500Y+075100               S0      
317GND              VIA        MD0040PA00X+012500Y+075850               S0      
317GND              VIA        MD0040PA00X+012500Y+086850               S0      
317GND              VIA        MD0040PA00X+012500Y+096700               S0      
317GND              VIA        MD0040PA00X+012550Y+074150               S0      
317GND              VIA        MD0040PA00X+012550Y+092000               S0      
317GND              VIA        MD0040PA00X+012550Y+094400               S0      
317GND              VIA        MD0040PA00X+001260Y+175380               S0      
317GND              VIA        MD0040PA00X+001260Y+179280               S0      
317GND              VIA        MD0040PA00X+012600Y+089250               S0      
317GND              VIA        MD0040PA00X+012600Y+093000               S0      
317GND              VIA        MD0040PA00X+012600Y+095400               S0      
317GND              VIA        MD0040PA00X+012660Y+146150               S0      
317GND              VIA        MD0040PA00X+012700Y+090300               S0      
317GND              VIA        MD0040PA00X+012770Y+011920               S0      
317GND              VIA        MD0040PA00X+012850Y+008900               S0      
317GND              VIA        MD0040PA00X+012870Y+010420               S0      
317GND              VIA        MD0040PA00X+001290Y+176520               S0      
317GND              VIA        MD0040PA00X+012900Y+016010               S0      
317GND              VIA        MD0040PA00X+012900Y+077450               S0      
317GND              VIA        MD0040PA00X+012920Y+083040               S0      
317GND              VIA        MD0040PA00X+012950Y+078200               S0      
317GND              VIA        MD0040PA00X+012950Y+079250               S0      
317GND              VIA        MD0040PA00X+012980Y+069680               S0      
317GND              VIA        MD0040PA00X+012980Y+081350               S0      
317GND              VIA        MD0040PA00X+001300Y+021250               S0      
317GND              VIA        MD0040PA00X+001300Y+024400               S0      
317GND              VIA        MD0040PA00X+001300Y+032100               S0      
317GND              VIA        MD0040PA00X+013000Y+073650               S0      
317GND              VIA        MD0040PA00X+013000Y+080000               S0      
317GND              VIA        MD0040PA00X+013050Y+096600               S0      
317GND              VIA        MD0040PA00X+013090Y+025910               S0      
317GND              VIA        MD0040PA00X+001310Y+172890               S0      
317GND              VIA        MD0040PA00X+001310Y+174260               S0      
317GND              VIA        MD0040PA00X+001310Y+193390               S0      
317GND              VIA        MD0040PA00X+013100Y+013810               S0      
317GND              VIA        MD0040PA00X+013100Y+015010               S0      
317GND              VIA        MD0040PA00X+013180Y+028970               S0      
317GND              VIA        MD0040PA00X+013220Y+142480               S0      
317GND              VIA        MD0040PA00X+013350Y+146710               S0      
317GND              VIA        MD0040PA00X+013350Y+093800               S0      
317GND              VIA        MD0040PA00X+013400Y+099050               S0      
317GND              VIA        MD0040PA00X+013410Y+067450               S0      
317GND              VIA        MD0040PA00X+013450Y+084050               S0      
317GND              VIA        MD0040PA00X+013450Y+088550               S0      
317GND              VIA        MD0040PA00X+001350Y+136500               S0      
317GND              VIA        MD0040PA00X+001350Y+023050               S0      
317GND              VIA        MD0040PA00X+001350Y+027900               S0      
317GND              VIA        MD0040PA00X+001350Y+029500               S0      
317GND              VIA        MD0040PA00X+001350Y+030350               S0      
317GND              VIA        MD0040PA00X+001351Y+059799               S0      
317GND              VIA        MD0040PA00X+013500Y+004500               S0      
317GND              VIA        MD0040PA00X+013500Y+005000               S0      
317GND              VIA        MD0040PA00X+013500Y+007000               S0      
317GND              VIA        MD0040PA00X+013500Y+089300               S0      
317GND              VIA        MD0040PA00X+013500Y+091800               S0      
317GND              VIA        MD0040PA00X+013500Y+097550               S0      
317GND              VIA        MD0040PA00X+013550Y+090900               S0      
317GND              VIA        MD0040PA00X+013550Y+092750               S0      
317GND              VIA        MD0040PA00X+013650Y+096700               S0      
317GND              VIA        MD0040PA00X+013700Y+142920               S0      
317GND              VIA        MD0040PA00X+013720Y+012360               S0      
317GND              VIA        MD0040PA00X+013750Y+087650               S0      
317GND              VIA        MD0040PA00X+013750Y+090300               S0      
317GND              VIA        MD0040PA00X+013790Y+017140               S0      
317GND              VIA        MD0040PA00X+013880Y+016210               S0      
317GND              VIA        MD0040PA00X+001400Y+106000               S0      
317GND              VIA        MD0040PA00X+001400Y+107400               S0      
317GND              VIA        MD0040PA00X+001400Y+108600               S0      
317GND              VIA        MD0040PA00X+001400Y+110000               S0      
317GND              VIA        MD0040PA00X+001400Y+014100               S0      
317GND              VIA        MD0040PA00X+001400Y+018400               S0      
317GND              VIA        MD0040PA00X+001400Y+061400               S0      
317GND              VIA        MD0040PA00X+001400Y+065900               S0      
317GND              VIA        MD0040PA00X+014050Y+084650               S0      
317GND              VIA        MD0040PA00X+014070Y+057660               S0      
317GND              VIA        MD0040PA00X+014100Y+093850               S0      
317GND              VIA        MD0040PA00X+014130Y+029810               S0      
317GND              VIA        MD0040PA00X+014150Y+167300               S0      
317GND              VIA        MD0040PA00X+014180Y+055925               S0      
317GND              VIA        MD0040PA00X+014300Y+091050               S0      
317GND              VIA        MD0040PA00X+014400Y+091950               S0      
317GND              VIA        MD0040PA00X+014400Y+092900               S0      
317GND              VIA        MD0040PA00X+014460Y+053380               S0      
317GND              VIA        MD0040PA00X+001450Y+010050               S0      
317GND              VIA        MD0040PA00X+001450Y+011250               S0      
317GND              VIA        MD0040PA00X+001450Y+183250               S0      
317GND              VIA        MD0040PA00X+001450Y+184200               S0      
317GND              VIA        MD0040PA00X+001450Y+186350               S0      
317GND              VIA        MD0040PA00X+014500Y+004500               S0      
317GND              VIA        MD0040PA00X+014550Y+060400               S0      
317GND              VIA        MD0040PA00X+014550Y+085650               S0      
317GND              VIA        MD0040PA00X+014550Y+088500               S0      
317GND              VIA        MD0040PA00X+014600Y+089300               S0      
317GND              VIA        MD0040PA00X+014650Y+124150               S0      
317GND              VIA        MD0040PA00X+014650Y+013186               S0      
317GND              VIA        MD0040PA00X+014650Y+141762               S0      
317GND              VIA        MD0040PA00X+014700Y+126550               S0      
317GND              VIA        MD0040PA00X+014700Y+134800               S0      
317GND              VIA        MD0040PA00X+014700Y+137700               S0      
317GND              VIA        MD0040PA00X+014750Y+116550               S0      
317GND              VIA        MD0040PA00X+014750Y+118600               S0      
317GND              VIA        MD0040PA00X+014750Y+122150               S0      
317GND              VIA        MD0040PA00X+014750Y+128800               S0      
317GND              VIA        MD0040PA00X+014750Y+131100               S0      
317GND              VIA        MD0040PA00X+014750Y+133200               S0      
317GND              VIA        MD0040PA00X+014750Y+136650               S0      
317GND              VIA        MD0040PA00X+014750Y+055150               S0      
317GND              VIA        MD0040PA00X+014760Y+015090               S0      
317GND              VIA        MD0040PA00X+014969Y+146001               S0      
317GND              VIA        MD0040PA00X+001500Y+013150               S0      
317GND              VIA        MD0040PA00X+001500Y+185490               S0      
317GND              VIA        MD0040PA00X+015050Y+059600               S0      
317GND              VIA        MD0040PA00X+015300Y+009050               S0      
317GND              VIA        MD0040PA00X+015350Y+057436               S0      
317GND              VIA        MD0040PA00X+015350Y+094100               S0      
317GND              VIA        MD0040PA00X+015400Y+010550               S0      
317GND              VIA        MD0040PA00X+015400Y+007550               S0      
317GND              VIA        MD0040PA00X+015450Y+092650               S0      
317GND              VIA        MD0040PA00X+015460Y+111100               S0      
317GND              VIA        MD0040PA00X+015470Y+090970               S0      
317GND              VIA        MD0040PA00X+001550Y+194250               S0      
317GND              VIA        MD0040PA00X+015500Y+004500               S0      
317GND              VIA        MD0040PA00X+015630Y+087720               S0      
317GND              VIA        MD0040PA00X+015650Y+088900               S0      
317GND              VIA        MD0040PA00X+015700Y+110150               S0      
317GND              VIA        MD0040PA00X+015750Y+085800               S0      
317GND              VIA        MD0040PA00X+015850Y+107580               S0      
317GND              VIA        MD0040PA00X+015860Y+111079               S0      
317GND              VIA        MD0040PA00X+015950Y+108750               S0      
317GND              VIA        MD0040PA00X+015970Y+065200               S0      
317GND              VIA        MD0040PA00X+001600Y+100000               S0      
317GND              VIA        MD0040PA00X+001600Y+101400               S0      
317GND              VIA        MD0040PA00X+001600Y+103200               S0      
317GND              VIA        MD0040PA00X+001600Y+104600               S0      
317GND              VIA        MD0040PA00X+001600Y+111000               S0      
317GND              VIA        MD0040PA00X+001600Y+112400               S0      
317GND              VIA        MD0040PA00X+001600Y+113400               S0      
317GND              VIA        MD0040PA00X+001600Y+114800               S0      
317GND              VIA        MD0040PA00X+001600Y+116200               S0      
317GND              VIA        MD0040PA00X+001600Y+117600               S0      
317GND              VIA        MD0040PA00X+001600Y+124400               S0      
317GND              VIA        MD0040PA00X+001600Y+126200               S0      
317GND              VIA        MD0040PA00X+001600Y+081400               S0      
317GND              VIA        MD0040PA00X+001600Y+082800               S0      
317GND              VIA        MD0040PA00X+001600Y+084200               S0      
317GND              VIA        MD0040PA00X+001600Y+085600               S0      
317GND              VIA        MD0040PA00X+001600Y+090600               S0      
317GND              VIA        MD0040PA00X+001600Y+094800               S0      
317GND              VIA        MD0040PA00X+001600Y+096200               S0      
317GND              VIA        MD0040PA00X+001600Y+097600               S0      
317GND              VIA        MD0040PA00X+001600Y+099000               S0      
317GND              VIA        MD0040PA00X+016050Y+105350               S0      
317GND              VIA        MD0040PA00X+016050Y+106700               S0      
317GND              VIA        MD0040PA00X+016050Y+187750               S0      
317GND              VIA        MD0040PA00X+001610Y+195070               S0      
317GND              VIA        MD0040PA00X+001610Y+079460               S0      
317GND              VIA        MD0040PA00X+016100Y+190150               S0      
317GND              VIA        MD0040PA00X+016150Y+122750               S0      
317GND              VIA        MD0040PA00X+016230Y+065910               S0      
317GND              VIA        MD0040PA00X+016334Y+118120               S0      
317GND              VIA        MD0040PA00X+016350Y+080550               S0      
317GND              VIA        MD0040PA00X+016400Y+005550               S0      
317GND              VIA        MD0040PA00X+016450Y+129950               S0      
317GND              VIA        MD0040PA00X+016470Y+103360               S0      
317GND              VIA        MD0040PA00X+016495Y+061570               S0      
317GND              VIA        MD0040PA00X+001650Y+017500               S0      
317GND              VIA        MD0040PA00X+016500Y+109700               S0      
317GND              VIA        MD0040PA00X+016500Y+126450               S0      
317GND              VIA        MD0040PA00X+016500Y+004500               S0      
317GND              VIA        MD0040PA00X+016500Y+078600               S0      
317GND              VIA        MD0040PA00X+016530Y+014520               S0      
317GND              VIA        MD0040PA00X+016550Y+067750               S0      
317GND              VIA        MD0040PA00X+016550Y+009550               S0      
317GND              VIA        MD0040PA00X+016560Y+063027               S0      
317GND              VIA        MD0040PA00X+016600Y+108000               S0      
317GND              VIA        MD0040PA00X+016630Y+102130               S0      
317GND              VIA        MD0040PA00X+016700Y+013050               S0      
317GND              VIA        MD0040PA00X+016730Y+065380               S0      
317GND              VIA        MD0040PA00X+016900Y+079550               S0      
317GND              VIA        MD0040PA00X+016910Y+072210               S0      
317GND              VIA        MD0040PA00X+001700Y+003650               S0      
317GND              VIA        MD0040PA00X+017000Y+108950               S0      
317GND              VIA        MD0040PA00X+017000Y+110300               S0      
317GND              VIA        MD0040PA00X+017050Y+012050               S0      
317GND              VIA        MD0040PA00X+017100Y+103250               S0      
317GND              VIA        MD0040PA00X+017100Y+104600               S0      
317GND              VIA        MD0040PA00X+017100Y+106800               S0      
317GND              VIA        MD0040PA00X+017150Y+010550               S0      
317GND              VIA        MD0040PA00X+017150Y+081950               S0      
317GND              VIA        MD0040PA00X+017150Y+112955               S0      
317GND              VIA        MD0040PA00X+017160Y+059540               S0      
317GND              VIA        MD0040PA00X+017200Y+075750               S0      
317GND              VIA        MD0040PA00X+017300Y+108200               S0      
317GND              VIA        MD0040PA00X+017338Y+143250               S0      
317GND              VIA        MD0040PA00X+017350Y+015150               S0      
317GND              VIA        MD0040PA00X+017350Y+076400               S0      
317GND              VIA        MD0040PA00X+017350Y+077750               S0      
317GND              VIA        MD0040PA00X+017400Y+101240               S0      
317GND              VIA        MD0040PA00X+017400Y+005550               S0      
317GND              VIA        MD0040PA00X+017450Y+014350               S0      
317GND              VIA        MD0040PA00X+017500Y+105900               S0      
317GND              VIA        MD0040PA00X+017500Y+107250               S0      
317GND              VIA        MD0040PA00X+017500Y+004500               S0      
317GND              VIA        MD0040PA00X+017500Y+078650               S0      
317GND              VIA        MD0040PA00X+017580Y+061764               S0      
317GND              VIA        MD0040PA00X+017600Y+101850               S0      
317GND              VIA        MD0040PA00X+017600Y+013100               S0      
317GND              VIA        MD0040PA00X+017600Y+066550               S0      
317GND              VIA        MD0040PA00X+017600Y+067900               S0      
317GND              VIA        MD0040PA00X+001770Y+128300               S0      
317GND              VIA        MD0040PA00X+017710Y+112980               S0      
317GND              VIA        MD0040PA00X+017750Y+081200               S0      
317GND              VIA        MD0040PA00X+017750Y+082650               S0      
317GND              VIA        MD0040PA00X+017800Y+079750               S0      
317GND              VIA        MD0040PA00X+017864Y+120252               S0      
317GND              VIA        MD0040PA00X+001800Y+060800               S0      
317GND              VIA        MD0040PA00X+001800Y+071200               S0      
317GND              VIA        MD0040PA00X+001800Y+072400               S0      
317GND              VIA        MD0040PA00X+001800Y+073250               S0      
317GND              VIA        MD0040PA00X+001800Y+087000               S0      
317GND              VIA        MD0040PA00X+001800Y+088400               S0      
317GND              VIA        MD0040PA00X+001800Y+092000               S0      
317GND              VIA        MD0040PA00X+001800Y+093400               S0      
317GND              VIA        MD0040PA00X+018050Y+011200               S0      
317GND              VIA        MD0040PA00X+018050Y+059500               S0      
317GND              VIA        MD0040PA00X+018050Y+062777               S0      
317GND              VIA        MD0040PA00X+018085Y+034880               S0      
317GND              VIA        MD0040PA00X+018100Y+105100               S0      
317GND              VIA        MD0040PA00X+018100Y+107950               S0      
317GND              VIA        MD0040PA00X+018100Y+109850               S0      
317GND              VIA        MD0040PA00X+018100Y+111250               S0      
317GND              VIA        MD0040PA00X+018100Y+071550               S0      
317GND              VIA        MD0040PA00X+018100Y+072900               S0      
317GND              VIA        MD0040PA00X+018110Y+036405               S0      
317GND              VIA        MD0040PA00X+018150Y+073850               S0      
317GND              VIA        MD0040PA00X+018170Y+076840               S0      
317GND              VIA        MD0040PA00X+018180Y+036900               S0      
317GND              VIA        MD0040PA00X+018200Y+101600               S0      
317GND              VIA        MD0040PA00X+018200Y+102950               S0      
317GND              VIA        MD0040PA00X+018200Y+095050               S0      
317GND              VIA        MD0040PA00X+018250Y+104150               S0      
317GND              VIA        MD0040PA00X+018250Y+074500               S0      
317GND              VIA        MD0040PA00X+018250Y+075850               S0      
317GND              VIA        MD0040PA00X+018260Y+054690               S0      
317GND              VIA        MD0040PA00X+018350Y+106550               S0      
317GND              VIA        MD0040PA00X+018350Y+124150               S0      
317GND              VIA        MD0040PA00X+018350Y+069800               S0      
317GND              VIA        MD0040PA00X+018400Y+005550               S0      
317GND              VIA        MD0040PA00X+018400Y+098750               S0      
317GND              VIA        MD0040PA00X+018450Y+032550               S0      
317GND              VIA        MD0040PA00X+018450Y+070850               S0      
317GND              VIA        MD0040PA00X+018450Y+086550               S0      
317GND              VIA        MD0040PA00X+018450Y+087900               S0      
317GND              VIA        MD0040PA00X+018470Y+066390               S0      
317GND              VIA        MD0040PA00X+001850Y+089650               S0      
317GND              VIA        MD0040PA00X+018500Y+004500               S0      
317GND              VIA        MD0040PA00X+018500Y+067350               S0      
317GND              VIA        MD0040PA00X+018500Y+084350               S0      
317GND              VIA        MD0040PA00X+018500Y+091750               S0      
317GND              VIA        MD0040PA00X+018550Y+015150               S0      
317GND              VIA        MD0040PA00X+001860Y+187140               S0      
317GND              VIA        MD0040PA00X+018600Y+014300               S0      
317GND              VIA        MD0040PA00X+018660Y+042575               S0      
317GND              VIA        MD0040PA00X+018700Y+089100               S0      
317GND              VIA        MD0040PA00X+018750Y+109000               S0      
317GND              VIA        MD0040PA00X+018750Y+110350               S0      
317GND              VIA        MD0040PA00X+018750Y+013050               S0      
317GND              VIA        MD0040PA00X+018750Y+033800               S0      
317GND              VIA        MD0040PA00X+018790Y+078530               S0      
317GND              VIA        MD0040PA00X+018810Y+068910               S0      
317GND              VIA        MD0040PA00X+018830Y+036860               S0      
317GND              VIA        MD0040PA00X+018850Y+036410               S0      
317GND              VIA        MD0040PA00X+018950Y+012000               S0      
317GND              VIA        MD0040PA00X+019000Y+105200               S0      
317GND              VIA        MD0040PA00X+019000Y+082350               S0      
317GND              VIA        MD0040PA00X+019050Y+010500               S0      
317GND              VIA        MD0040PA00X+019050Y+192400               S0      
317GND              VIA        MD0040PA00X+019050Y+055050               S0      
317GND              VIA        MD0040PA00X+019050Y+083100               S0      
317GND              VIA        MD0040PA00X+019150Y+069250               S0      
317GND              VIA        MD0040PA00X+019150Y+071050               S0      
317GND              VIA        MD0040PA00X+019150Y+072400               S0      
317GND              VIA        MD0040PA00X+019150Y+074650               S0      
317GND              VIA        MD0040PA00X+019150Y+076000               S0      
317GND              VIA        MD0040PA00X+019160Y+020690               S0      
317GND              VIA        MD0040PA00X+019170Y+018650               S0      
317GND              VIA        MD0040PA00X+019180Y+128090               S0      
317GND              VIA        MD0040PA00X+019180Y+022110               S0      
317GND              VIA        MD0040PA00X+019180Y+023490               S0      
317GND              VIA        MD0040PA00X+019190Y+016770               S0      
317GND              VIA        MD0040PA00X+019190Y+024460               S0      
317GND              VIA        MD0040PA00X+019190Y+053820               S0      
317GND              VIA        MD0040PA00X+019200Y+054350               S0      
317GND              VIA        MD0040PA00X+019200Y+086550               S0      
317GND              VIA        MD0040PA00X+019200Y+087900               S0      
317GND              VIA        MD0040PA00X+019200Y+092100               S0      
317GND              VIA        MD0040PA00X+019200Y+093450               S0      
317GND              VIA        MD0040PA00X+019200Y+094850               S0      
317GND              VIA        MD0040PA00X+019200Y+096200               S0      
317GND              VIA        MD0040PA00X+019230Y+041095               S0      
317GND              VIA        MD0040PA00X+019240Y+040190               S0      
317GND              VIA        MD0040PA00X+019240Y+052940               S0      
317GND              VIA        MD0040PA00X+019241Y+041766               S0      
317GND              VIA        MD0040PA00X+019247Y+039735               S0      
317GND              VIA        MD0040PA00X+019250Y+153300               S0      
317GND              VIA        MD0040PA00X+019250Y+154350               S0      
317GND              VIA        MD0040PA00X+019250Y+155400               S0      
317GND              VIA        MD0040PA00X+019250Y+156250               S0      
317GND              VIA        MD0040PA00X+019250Y+161700               S0      
317GND              VIA        MD0040PA00X+019250Y+162650               S0      
317GND              VIA        MD0040PA00X+019250Y+163400               S0      
317GND              VIA        MD0040PA00X+019250Y+166400               S0      
317GND              VIA        MD0040PA00X+019250Y+167050               S0      
317GND              VIA        MD0040PA00X+019250Y+064500               S0      
317GND              VIA        MD0040PA00X+019250Y+065850               S0      
317GND              VIA        MD0040PA00X+019250Y+083950               S0      
317GND              VIA        MD0040PA00X+019250Y+085300               S0      
317GND              VIA        MD0040PA00X+019250Y+097200               S0      
317GND              VIA        MD0040PA00X+019250Y+098550               S0      
317GND              VIA        MD0040PA00X+019260Y+039260               S0      
317GND              VIA        MD0040PA00X+019260Y+063300               S0      
317GND              VIA        MD0040PA00X+019310Y+067900               S0      
317GND              VIA        MD0040PA00X+019350Y+102900               S0      
317GND              VIA        MD0040PA00X+019350Y+104250               S0      
317GND              VIA        MD0040PA00X+019370Y+059500               S0      
317GND              VIA        MD0040PA00X+019400Y+005550               S0      
317GND              VIA        MD0040PA00X+019400Y+061500               S0      
317GND              VIA        MD0040PA00X+019400Y+062850               S0      
317GND              VIA        MD0040PA00X+019400Y+089350               S0      
317GND              VIA        MD0040PA00X+019400Y+090700               S0      
317GND              VIA        MD0040PA00X+019440Y+058600               S0      
317GND              VIA        MD0040PA00X+019450Y+110050               S0      
317GND              VIA        MD0040PA00X+019450Y+076900               S0      
317GND              VIA        MD0040PA00X+019450Y+078250               S0      
317GND              VIA        MD0040PA00X+019500Y+106100               S0      
317GND              VIA        MD0040PA00X+019500Y+107450               S0      
317GND              VIA        MD0040PA00X+019500Y+108650               S0      
317GND              VIA        MD0040PA00X+019500Y+187400               S0      
317GND              VIA        MD0040PA00X+019500Y+004500               S0      
317GND              VIA        MD0040PA00X+019500Y+067000               S0      
317GND              VIA        MD0040PA00X+019550Y+100100               S0      
317GND              VIA        MD0040PA00X+019550Y+101450               S0      
317GND              VIA        MD0040PA00X+019550Y+190500               S0      
317GND              VIA        MD0040PA00X+019550Y+073900               S0      
317GND              VIA        MD0040PA00X+019600Y+071850               S0      
317GND              VIA        MD0040PA00X+019600Y+078950               S0      
317GND              VIA        MD0040PA00X+019650Y+158600               S0      
317GND              VIA        MD0040PA00X+019650Y+159500               S0      
317GND              VIA        MD0040PA00X+019650Y+064150               S0      
317GND              VIA        MD0040PA00X+019650Y+079700               S0      
317GND              VIA        MD0040PA00X+019680Y+082850               S0      
317GND              VIA        MD0040PA00X+001972Y+026720               S0      
317GND              VIA        MD0040PA00X+019700Y+070400               S0      
317GND              VIA        MD0040PA00X+019700Y+081500               S0      
317GND              VIA        MD0040PA00X+019750Y+015150               S0      
317GND              VIA        MD0040PA00X+019750Y+177650               S0      
317GND              VIA        MD0040PA00X+019750Y+180050               S0      
317GND              VIA        MD0040PA00X+019750Y+068500               S0      
317GND              VIA        MD0040PA00X+019750Y+075300               S0      
317GND              VIA        MD0040PA00X+001980Y+131540               S0      
317GND              VIA        MD0040PA00X+019800Y+169150               S0      
317GND              VIA        MD0040PA00X+019800Y+173550               S0      
317GND              VIA        MD0040PA00X+019800Y+175400               S0      
317GND              VIA        MD0040PA00X+019800Y+181850               S0      
317GND              VIA        MD0040PA00X+019800Y+183850               S0      
317GND              VIA        MD0040PA00X+019850Y+171350               S0      
317GND              VIA        MD0040PA00X+019850Y+185950               S0      
317GND              VIA        MD0040PA00X+002000Y+000600               S0      
317GND              VIA        MD0040PA00X+002000Y+069600               S0      
317GND              VIA        MD0040PA00X+020000Y+010000               S0      
317GND              VIA        MD0040PA00X+020000Y+012000               S0      
317GND              VIA        MD0040PA00X+020000Y+014000               S0      
317GND              VIA        MD0040PA00X+020000Y+188200               S0      
317GND              VIA        MD0040PA00X+020000Y+042050               S0      
317GND              VIA        MD0040PA00X+020000Y+005500               S0      
317GND              VIA        MD0040PA00X+020000Y+006500               S0      
317GND              VIA        MD0040PA00X+020000Y+007500               S0      
317GND              VIA        MD0040PA00X+020000Y+008500               S0      
317GND              VIA        MD0040PA00X+020050Y+019590               S0      
317GND              VIA        MD0040PA00X+020050Y+023500               S0      
317GND              VIA        MD0040PA00X+020050Y+043750               S0      
317GND              VIA        MD0040PA00X+020100Y+109300               S0      
317GND              VIA        MD0040PA00X+020100Y+110650               S0      
317GND              VIA        MD0040PA00X+020100Y+192300               S0      
317GND              VIA        MD0040PA00X+020100Y+022250               S0      
317GND              VIA        MD0040PA00X+020100Y+043050               S0      
317GND              VIA        MD0040PA00X+020109Y+018170               S0      
317GND              VIA        MD0040PA00X+020109Y+028260               S0      
317GND              VIA        MD0040PA00X+020109Y+030550               S0      
317GND              VIA        MD0040PA00X+020109Y+031550               S0      
317GND              VIA        MD0040PA00X+020109Y+038840               S0      
317GND              VIA        MD0040PA00X+020109Y+040700               S0      
317GND              VIA        MD0040PA00X+020109Y+052950               S0      
317GND              VIA        MD0040PA00X+020109Y+055800               S0      
317GND              VIA        MD0040PA00X+020109Y+057060               S0      
317GND              VIA        MD0040PA00X+020150Y+190050               S0      
317GND              VIA        MD0040PA00X+020150Y+020800               S0      
317GND              VIA        MD0040PA00X+020150Y+037800               S0      
317GND              VIA        MD0040PA00X+020150Y+039750               S0      
317GND              VIA        MD0040PA00X+020150Y+053500               S0      
317GND              VIA        MD0040PA00X+020150Y+054450               S0      
317GND              VIA        MD0040PA00X+020150Y+055250               S0      
317GND              VIA        MD0040PA00X+020150Y+056400               S0      
317GND              VIA        MD0040PA00X+020150Y+062150               S0      
317GND              VIA        MD0040PA00X+020150Y+083550               S0      
317GND              VIA        MD0040PA00X+020200Y+025400               S0      
317GND              VIA        MD0040PA00X+020200Y+026400               S0      
317GND              VIA        MD0040PA00X+020200Y+027400               S0      
317GND              VIA        MD0040PA00X+020200Y+029500               S0      
317GND              VIA        MD0040PA00X+020200Y+032800               S0      
317GND              VIA        MD0040PA00X+020200Y+034000               S0      
317GND              VIA        MD0040PA00X+020200Y+035300               S0      
317GND              VIA        MD0040PA00X+020200Y+036650               S0      
317GND              VIA        MD0040PA00X+020200Y+057800               S0      
317GND              VIA        MD0040PA00X+020200Y+058600               S0      
317GND              VIA        MD0040PA00X+020200Y+059500               S0      
317GND              VIA        MD0040PA00X+020200Y+060750               S0      
317GND              VIA        MD0040PA00X+020200Y+065050               S0      
317GND              VIA        MD0040PA00X+020200Y+067650               S0      
317GND              VIA        MD0040PA00X+020200Y+071000               S0      
317GND              VIA        MD0040PA00X+020200Y+074050               S0      
317GND              VIA        MD0040PA00X+020200Y+076500               S0      
317GND              VIA        MD0040PA00X+020200Y+078600               S0      
317GND              VIA        MD0040PA00X+020200Y+080750               S0      
317GND              VIA        MD0040PA00X+002150Y+024150               S0      
317GND              VIA        MD0040PA00X+002200Y+123200               S0      
317GND              VIA        MD0040PA00X+002200Y+074600               S0      
317GND              VIA        MD0040PA00X+002250Y+019000               S0      
317GND              VIA        MD0040PA00X+002300Y+067750               S0      
317GND              VIA        MD0040PA00X+002305Y+086125               S0      
317GND              VIA        MD0040PA00X+002350Y+012400               S0      
317GND              VIA        MD0040PA00X+002370Y+036390               S0      
317GND              VIA        MD0040PA00X+002380Y+041070               S0      
317GND              VIA        MD0040PA00X+002400Y+118000               S0      
317GND              VIA        MD0040PA00X+002400Y+021200               S0      
317GND              VIA        MD0040PA00X+002400Y+075600               S0      
317GND              VIA        MD0040PA00X+002400Y+084600               S0      
317GND              VIA        MD0040PA00X+002450Y+085350               S0      
317GND              VIA        MD0040PA00X+002455Y+115325               S0      
317GND              VIA        MD0040PA00X+002480Y+192650               S0      
317GND              VIA        MD0040PA00X+002500Y+196250               S0      
317GND              VIA        MD0040PA00X+002505Y+097125               S0      
317GND              VIA        MD0040PA00X+002600Y+101000               S0      
317GND              VIA        MD0040PA00X+002600Y+043250               S0      
317GND              VIA        MD0040PA00X+002600Y+065650               S0      
317GND              VIA        MD0040PA00X+002600Y+073200               S0      
317GND              VIA        MD0040PA00X+002600Y+008700               S0      
317GND              VIA        MD0040PA00X+002605Y+082825               S0      
317GND              VIA        MD0040PA00X+002605Y+093825               S0      
317GND              VIA        MD0040PA00X+002610Y+108860               S0      
317GND              VIA        MD0040PA00X+002650Y+044000               S0      
317GND              VIA        MD0040PA00X+002660Y+113240               S0      
317GND              VIA        MD0040PA00X+002660Y+157010               S0      
317GND              VIA        MD0040PA00X+002670Y+157980               S0      
317GND              VIA        MD0040PA00X+002690Y+154790               S0      
317GND              VIA        MD0040PA00X+002690Y+155910               S0      
317GND              VIA        MD0040PA00X+002700Y+018200               S0      
317GND              VIA        MD0040PA00X+002700Y+037100               S0      
317GND              VIA        MD0040PA00X+002700Y+037750               S0      
317GND              VIA        MD0040PA00X+002700Y+038400               S0      
317GND              VIA        MD0040PA00X+002700Y+038950               S0      
317GND              VIA        MD0040PA00X+002700Y+075000               S0      
317GND              VIA        MD0040PA00X+002722Y+109700               S0      
317GND              VIA        MD0040PA00X+002750Y+188350               S0      
317GND              VIA        MD0040PA00X+002755Y+102925               S0      
317GND              VIA        MD0040PA00X+002800Y+107200               S0      
317GND              VIA        MD0040PA00X+002800Y+126600               S0      
317GND              VIA        MD0040PA00X+002800Y+128600               S0      
317GND              VIA        MD0040PA00X+002800Y+130000               S0      
317GND              VIA        MD0040PA00X+002800Y+132000               S0      
317GND              VIA        MD0040PA00X+002800Y+187650               S0      
317GND              VIA        MD0040PA00X+002800Y+070600               S0      
317GND              VIA        MD0040PA00X+002800Y+099200               S0      
317GND              VIA        MD0040PA00X+002900Y+167100               S0      
317GND              VIA        MD0040PA00X+002900Y+184100               S0      
317GND              VIA        MD0040PA00X+002900Y+020050               S0      
317GND              VIA        MD0040PA00X+002950Y+149580               S0      
317GND              VIA        MD0040PA00X+002950Y+036450               S0      
317GND              VIA        MD0040PA00X+002950Y+005300               S0      
317GND              VIA        MD0040PA00X+002970Y+019140               S0      
317GND              VIA        MD0040PA00X+003000Y+124000               S0      
317GND              VIA        MD0040PA00X+003000Y+173100               S0      
317GND              VIA        MD0040PA00X+003000Y+078200               S0      
317GND              VIA        MD0040PA00X+003050Y+081950               S0      
317GND              VIA        MD0040PA00X+003080Y+013030               S0      
317GND              VIA        MD0040PA00X+003080Y+140390               S0      
317GND              VIA        MD0040PA00X+003100Y+070050               S0      
317GND              VIA        MD0040PA00X+003100Y+074700               S0      
317GND              VIA        MD0040PA00X+003150Y+122200               S0      
317GND              VIA        MD0040PA00X+003150Y+139750               S0      
317GND              VIA        MD0040PA00X+003150Y+000550               S0      
317GND              VIA        MD0040PA00X+003200Y+111400               S0      
317GND              VIA        MD0040PA00X+003200Y+139150               S0      
317GND              VIA        MD0040PA00X+003200Y+004000               S0      
317GND              VIA        MD0040PA00X+003200Y+066600               S0      
317GND              VIA        MD0040PA00X+003200Y+084400               S0      
317GND              VIA        MD0040PA00X+003200Y+085800               S0      
317GND              VIA        MD0040PA00X+003200Y+087200               S0      
317GND              VIA        MD0040PA00X+003200Y+088600               S0      
317GND              VIA        MD0040PA00X+003310Y+158740               S0      
317GND              VIA        MD0040PA00X+003350Y+095300               S0      
317GND              VIA        MD0040PA00X+003350Y+096250               S0      
317GND              VIA        MD0040PA00X+003355Y+108010               S0      
317GND              VIA        MD0040PA00X+003360Y+102990               S0      
317GND              VIA        MD0040PA00X+003400Y+100800               S0      
317GND              VIA        MD0040PA00X+003400Y+101750               S0      
317GND              VIA        MD0040PA00X+003400Y+107200               S0      
317GND              VIA        MD0040PA00X+003400Y+110200               S0      
317GND              VIA        MD0040PA00X+003400Y+114400               S0      
317GND              VIA        MD0040PA00X+003400Y+131200               S0      
317GND              VIA        MD0040PA00X+003400Y+146590               S0      
317GND              VIA        MD0040PA00X+003400Y+147760               S0      
317GND              VIA        MD0040PA00X+003400Y+093450               S0      
317GND              VIA        MD0040PA00X+003400Y+094400               S0      
317GND              VIA        MD0040PA00X+003400Y+097450               S0      
317GND              VIA        MD0040PA00X+003400Y+098400               S0      
317GND              VIA        MD0040PA00X+003410Y+056660               S0      
317GND              VIA        MD0040PA00X+003440Y+009530               S0      
317GND              VIA        MD0040PA00X+003450Y+196320               S0      
317GND              VIA        MD0040PA00X+003500Y+193350               S0      
317GND              VIA        MD0040PA00X+003530Y+192530               S0      
317GND              VIA        MD0040PA00X+003600Y+055400               S0      
317GND              VIA        MD0040PA00X+003600Y+073000               S0      
317GND              VIA        MD0040PA00X+003650Y+190050               S0      
317GND              VIA        MD0040PA00X+003670Y+176470               S0      
317GND              VIA        MD0040PA00X+003700Y+012400               S0      
317GND              VIA        MD0040PA00X+003750Y+111890               S0      
317GND              VIA        MD0040PA00X+003750Y+090750               S0      
317GND              VIA        MD0040PA00X+003750Y+091200               S0      
317GND              VIA        MD0040PA00X+003790Y+157000               S0      
317GND              VIA        MD0040PA00X+003800Y+082000               S0      
317GND              VIA        MD0040PA00X+003800Y+083400               S0      
317GND              VIA        MD0040PA00X+003830Y+156180               S0      
317GND              VIA        MD0040PA00X+003830Y+157960               S0      
317GND              VIA        MD0040PA00X+003880Y+154170               S0      
317GND              VIA        MD0040PA00X+003900Y+133350               S0      
317GND              VIA        MD0040PA00X+003950Y+123100               S0      
317GND              VIA        MD0040PA00X+003950Y+140790               S0      
317GND              VIA        MD0040PA00X+003970Y+186970               S0      
317GND              VIA        MD0040PA00X+004000Y+113600               S0      
317GND              VIA        MD0040PA00X+004000Y+115600               S0      
317GND              VIA        MD0040PA00X+004000Y+127800               S0      
317GND              VIA        MD0040PA00X+004000Y+129800               S0      
317GND              VIA        MD0040PA00X+004000Y+074650               S0      
317GND              VIA        MD0040PA00X+004059Y+000600               S0      
317GND              VIA        MD0040PA00X+004090Y+090150               S0      
317GND              VIA        MD0040PA00X+004110Y+195750               S0      
317GND              VIA        MD0040PA00X+004200Y+124200               S0      
317GND              VIA        MD0040PA00X+004200Y+126600               S0      
317GND              VIA        MD0040PA00X+004200Y+129000               S0      
317GND              VIA        MD0040PA00X+004200Y+078800               S0      
317GND              VIA        MD0040PA00X+004200Y+080200               S0      
317GND              VIA        MD0040PA00X+004250Y+169950               S0      
317GND              VIA        MD0040PA00X+004260Y+144420               S0      
317GND              VIA        MD0040PA00X+004270Y+150000               S0      
317GND              VIA        MD0040PA00X+004300Y+002700               S0      
317GND              VIA        MD0040PA00X+004320Y+163480               S0      
317GND              VIA        MD0040PA00X+004330Y+151850               S0      
317GND              VIA        MD0040PA00X+004350Y+194500               S0      
317GND              VIA        MD0040PA00X+004400Y+119400               S0      
317GND              VIA        MD0040PA00X+004400Y+130600               S0      
317GND              VIA        MD0040PA00X+004400Y+132600               S0      
317GND              VIA        MD0040PA00X+004400Y+134000               S0      
317GND              VIA        MD0040PA00X+004400Y+078200               S0      
317GND              VIA        MD0040PA00X+004440Y+159210               S0      
317GND              VIA        MD0040PA00X+004450Y+183350               S0      
317GND              VIA        MD0040PA00X+004460Y+172440               S0      
317GND              VIA        MD0040PA00X+004490Y+170680               S0      
317GND              VIA        MD0040PA00X+004490Y+174030               S0      
317GND              VIA        MD0040PA00X+000450Y+102950               S0      
317GND              VIA        MD0040PA00X+000450Y+010550               S0      
317GND              VIA        MD0040PA00X+000450Y+017050               S0      
317GND              VIA        MD0040PA00X+000450Y+193600               S0      
317GND              VIA        MD0040PA00X+000450Y+020250               S0      
317GND              VIA        MD0040PA00X+000450Y+083350               S0      
317GND              VIA        MD0040PA00X+000450Y+085750               S0      
317GND              VIA        MD0040PA00X+000450Y+091300               S0      
317GND              VIA        MD0040PA00X+000450Y+094150               S0      
317GND              VIA        MD0040PA00X+000450Y+097000               S0      
317GND              VIA        MD0040PA00X+000450Y+099700               S0      
317GND              VIA        MD0040PA00X+000459Y+101350               S0      
317GND              VIA        MD0040PA00X+000459Y+104150               S0      
317GND              VIA        MD0040PA00X+000459Y+116950               S0      
317GND              VIA        MD0040PA00X+000459Y+012050               S0      
317GND              VIA        MD0040PA00X+000459Y+138200               S0      
317GND              VIA        MD0040PA00X+000459Y+143550               S0      
317GND              VIA        MD0040PA00X+000459Y+160750               S0      
317GND              VIA        MD0040PA00X+000459Y+163200               S0      
317GND              VIA        MD0040PA00X+000459Y+169100               S0      
317GND              VIA        MD0040PA00X+000459Y+175100               S0      
317GND              VIA        MD0040PA00X+000459Y+177500               S0      
317GND              VIA        MD0040PA00X+000459Y+185000               S0      
317GND              VIA        MD0040PA00X+000459Y+018750               S0      
317GND              VIA        MD0040PA00X+000459Y+187850               S0      
317GND              VIA        MD0040PA00X+000459Y+190200               S0      
317GND              VIA        MD0040PA00X+000459Y+023400               S0      
317GND              VIA        MD0040PA00X+000459Y+039650               S0      
317GND              VIA        MD0040PA00X+000459Y+042100               S0      
317GND              VIA        MD0040PA00X+000459Y+062500               S0      
317GND              VIA        MD0040PA00X+000459Y+095400               S0      
317GND              VIA        MD0040PA00X+004510Y+193340               S0      
317GND              VIA        MD0040PA00X+004530Y+156360               S0      
317GND              VIA        MD0040PA00X+004540Y+152380               S0      
317GND              VIA        MD0040PA00X+004560Y+082750               S0      
317GND              VIA        MD0040PA00X+004590Y+153280               S0      
317GND              VIA        MD0040PA00X+000460Y+148480               S0      
317GND              VIA        MD0040PA00X+004600Y+121800               S0      
317GND              VIA        MD0040PA00X+004600Y+192300               S0      
317GND              VIA        MD0040PA00X+004600Y+072600               S0      
317GND              VIA        MD0040PA00X+004600Y+083400               S0      
317GND              VIA        MD0040PA00X+004600Y+084800               S0      
317GND              VIA        MD0040PA00X+004650Y+148490               S0      
317GND              VIA        MD0040PA00X+004650Y+184400               S0      
317GND              VIA        MD0040PA00X+004650Y+185020               S0      
317GND              VIA        MD0040PA00X+004650Y+186550               S0      
317GND              VIA        MD0040PA00X+004660Y+154110               S0      
317GND              VIA        MD0040PA00X+004670Y+185770               S0      
317GND              VIA        MD0040PA00X+000470Y+167610               S0      
317GND              VIA        MD0040PA00X+000470Y+045820               S0      
317GND              VIA        MD0040PA00X+004700Y+087760               S0      
317GND              VIA        MD0040PA00X+004760Y+079680               S0      
317GND              VIA        MD0040PA00X+000480Y+146070               S0      
317GND              VIA        MD0040PA00X+000480Y+035620               S0      
317GND              VIA        MD0040PA00X+004800Y+081600               S0      
317GND              VIA        MD0040PA00X+004810Y+085340               S0      
317GND              VIA        MD0040PA00X+004890Y+139050               S0      
317GND              VIA        MD0040PA00X+000490Y+170800               S0      
317GND              VIA        MD0040PA00X+000490Y+032800               S0      
317GND              VIA        MD0040PA00X+004900Y+141330               S0      
317GND              VIA        MD0040PA00X+004900Y+001850               S0      
317GND              VIA        MD0040PA00X+004905Y+195175               S0      
317GND              VIA        MD0040PA00X+004910Y+144840               S0      
317GND              VIA        MD0040PA00X+004950Y+150500               S0      
317GND              VIA        MD0040PA00X+000500Y+013750               S0      
317GND              VIA        MD0040PA00X+000500Y+186410               S0      
317GND              VIA        MD0040PA00X+000500Y+022100               S0      
317GND              VIA        MD0040PA00X+000500Y+024750               S0      
317GND              VIA        MD0040PA00X+000500Y+040850               S0      
317GND              VIA        MD0040PA00X+000500Y+048650               S0      
317GND              VIA        MD0040PA00X+000500Y+049500               S0      
317GND              VIA        MD0040PA00X+000500Y+088350               S0      
317GND              VIA        MD0040PA00X+000509Y+107450               S0      
317GND              VIA        MD0040PA00X+000509Y+126850               S0      
317GND              VIA        MD0040PA00X+000509Y+192100               S0      
317GND              VIA        MD0040PA00X+000509Y+194450               S0      
317GND              VIA        MD0040PA00X+000509Y+027800               S0      
317GND              VIA        MD0040PA00X+000509Y+046950               S0      
317GND              VIA        MD0040PA00X+000509Y+060000               S0      
317GND              VIA        MD0040PA00X+000509Y+089750               S0      
317GND              VIA        MD0040PA00X+005000Y+124400               S0      
317GND              VIA        MD0040PA00X+005000Y+131800               S0      
317GND              VIA        MD0040PA00X+005000Y+071250               S0      
317GND              VIA        MD0040PA00X+005000Y+074900               S0      
317GND              VIA        MD0040PA00X+005010Y+126150               S0      
317GND              VIA        MD0040PA00X+005150Y+005300               S0      
317GND              VIA        MD0040PA00X+005170Y+013170               S0      
317GND              VIA        MD0040PA00X+005180Y+123160               S0      
317GND              VIA        MD0040PA00X+005190Y+014570               S0      
317GND              VIA        MD0040PA00X+005200Y+011560               S0      
317GND              VIA        MD0040PA00X+005200Y+129630               S0      
317GND              VIA        MD0040PA00X+005250Y+136850               S0      
317GND              VIA        MD0040PA00X+000530Y+120800               S0      
317GND              VIA        MD0040PA00X+000530Y+140940               S0      
317GND              VIA        MD0040PA00X+000530Y+150410               S0      
317GND              VIA        MD0040PA00X+000530Y+152210               S0      
317GND              VIA        MD0040PA00X+000530Y+154050               S0      
317GND              VIA        MD0040PA00X+000530Y+157620               S0      
317GND              VIA        MD0040PA00X+000530Y+165900               S0      
317GND              VIA        MD0040PA00X+000530Y+172350               S0      
317GND              VIA        MD0040PA00X+000530Y+034250               S0      
317GND              VIA        MD0040PA00X+000530Y+043450               S0      
317GND              VIA        MD0040PA00X+000530Y+044050               S0      
317GND              VIA        MD0040PA00X+000530Y+044450               S0      
317GND              VIA        MD0040PA00X+000530Y+066100               S0      
317GND              VIA        MD0040PA00X+000530Y+092600               S0      
317GND              VIA        MD0040PA00X+005300Y+175050               S0      
317GND              VIA        MD0040PA00X+005300Y+000500               S0      
317GND              VIA        MD0040PA00X+005310Y+143070               S0      
317GND              VIA        MD0040PA00X+005400Y+118400               S0      
317GND              VIA        MD0040PA00X+005400Y+133000               S0      
317GND              VIA        MD0040PA00X+005400Y+192850               S0      
317GND              VIA        MD0040PA00X+005450Y+188950               S0      
317GND              VIA        MD0040PA00X+000550Y+026950               S0      
317GND              VIA        MD0040PA00X+000550Y+029550               S0      
317GND              VIA        MD0040PA00X+000559Y+015350               S0      
317GND              VIA        MD0040PA00X+000559Y+031200               S0      
317GND              VIA        MD0040PA00X+000559Y+005350               S0      
317GND              VIA        MD0040PA00X+000559Y+068850               S0      
317GND              VIA        MD0040PA00X+000559Y+077800               S0      
317GND              VIA        MD0040PA00X+000559Y+084450               S0      
317GND              VIA        MD0040PA00X+000559Y+086900               S0      
317GND              VIA        MD0040PA00X+000559Y+008700               S0      
317GND              VIA        MD0040PA00X+000559Y+098450               S0      
317GND              VIA        MD0040PA00X+005530Y+195910               S0      
317GND              VIA        MD0040PA00X+005550Y+095550               S0      
317GND              VIA        MD0040PA00X+005550Y+096800               S0      
317GND              VIA        MD0040PA00X+005560Y+138170               S0      
317GND              VIA        MD0040PA00X+005650Y+176930               S0      
317GND              VIA        MD0040PA00X+005650Y+094000               S0      
317GND              VIA        MD0040PA00X+005670Y+140010               S0      
317GND              VIA        MD0040PA00X+005800Y+120600               S0      
317GND              VIA        MD0040PA00X+005800Y+122200               S0      
317GND              VIA        MD0040PA00X+005800Y+125000               S0      
317GND              VIA        MD0040PA00X+005800Y+127200               S0      
317GND              VIA        MD0040PA00X+005800Y+129200               S0      
317GND              VIA        MD0040PA00X+005800Y+131200               S0      
317GND              VIA        MD0040PA00X+005810Y+145930               S0      
317GND              VIA        MD0040PA00X+005880Y+141240               S0      
317GND              VIA        MD0040PA00X+005900Y+144450               S0      
317GND              VIA        MD0040PA00X+005900Y+147200               S0      
317GND              VIA        MD0040PA00X+000600Y+105800               S0      
317GND              VIA        MD0040PA00X+000600Y+109600               S0      
317GND              VIA        MD0040PA00X+000600Y+111800               S0      
317GND              VIA        MD0040PA00X+000600Y+113800               S0      
317GND              VIA        MD0040PA00X+000600Y+115200               S0      
317GND              VIA        MD0040PA00X+000600Y+125200               S0      
317GND              VIA        MD0040PA00X+000600Y+131800               S0      
317GND              VIA        MD0040PA00X+000600Y+061200               S0      
317GND              VIA        MD0040PA00X+000600Y+064600               S0      
317GND              VIA        MD0040PA00X+000600Y+069800               S0      
317GND              VIA        MD0040PA00X+000600Y+070650               S0      
317GND              VIA        MD0040PA00X+000600Y+072200               S0      
317GND              VIA        MD0040PA00X+000600Y+073050               S0      
317GND              VIA        MD0040PA00X+000609Y+025700               S0      
317GND              VIA        MD0040PA00X+000609Y+081950               S0      
317GND              VIA        MD0040PA00X+006000Y+119400               S0      
317GND              VIA        MD0040PA00X+006060Y+142360               S0      
317GND              VIA        MD0040PA00X+006080Y+014770               S0      
317GND              VIA        MD0040PA00X+006090Y+139050               S0      
317GND              VIA        MD0040PA00X+006100Y+117300               S0      
317GND              VIA        MD0040PA00X+006100Y+136350               S0      
317GND              VIA        MD0040PA00X+006150Y+138000               S0      
317GND              VIA        MD0040PA00X+006150Y+192250               S0      
317GND              VIA        MD0040PA00X+006150Y+087650               S0      
317GND              VIA        MD0040PA00X+006150Y+093850               S0      
317GND              VIA        MD0040PA00X+006160Y+195470               S0      
317GND              VIA        MD0040PA00X+006250Y+086200               S0      
317GND              VIA        MD0040PA00X+006250Y+092450               S0      
317GND              VIA        MD0040PA00X+006260Y+014110               S0      
317GND              VIA        MD0040PA00X+006300Y+148230               S0      
317GND              VIA        MD0040PA00X+006310Y+011910               S0      
317GND              VIA        MD0040PA00X+006350Y+192800               S0      
317GND              VIA        MD0040PA00X+006350Y+196300               S0      
317GND              VIA        MD0040PA00X+006359Y+193550               S0      
317GND              VIA        MD0040PA00X+006359Y+002550               S0      
317GND              VIA        MD0040PA00X+006359Y+000700               S0      
317GND              VIA        MD0040PA00X+006400Y+001700               S0      
317GND              VIA        MD0040PA00X+006410Y+149540               S0      
317GND              VIA        MD0040PA00X+006450Y+004000               S0      
317GND              VIA        MD0040PA00X+000650Y+130200               S0      
317GND              VIA        MD0040PA00X+000650Y+196200               S0      
317GND              VIA        MD0040PA00X+000650Y+037500               S0      
317GND              VIA        MD0040PA00X+000650Y+079900               S0      
317GND              VIA        MD0040PA00X+006600Y+114950               S0      
317GND              VIA        MD0040PA00X+006650Y+143350               S0      
317GND              VIA        MD0040PA00X+006850Y+145460               S0      
317GND              VIA        MD0040PA00X+006880Y+141780               S0      
317GND              VIA        MD0040PA00X+006900Y+015300               S0      
317GND              VIA        MD0040PA00X+006910Y+069801               S0      
317GND              VIA        MD0040PA00X+006940Y+140290               S0      
317GND              VIA        MD0040PA00X+006950Y+093900               S0      
317GND              VIA        MD0040PA00X+006980Y+057420               S0      
317GND              VIA        MD0040PA00X+007000Y+091450               S0      
317GND              VIA        MD0040PA00X+007000Y+092550               S0      
317GND              VIA        MD0040PA00X+007040Y+144450               S0      
317GND              VIA        MD0040PA00X+007050Y+137850               S0      
317GND              VIA        MD0040PA00X+007100Y+013186               S0      
317GND              VIA        MD0040PA00X+007180Y+137390               S0      
317GND              VIA        MD0040PA00X+007180Y+070130               S0      
317GND              VIA        MD0040PA00X+007200Y+136000               S0      
317GND              VIA        MD0040PA00X+007230Y+146980               S0      
317GND              VIA        MD0040PA00X+007270Y+148050               S0      
317GND              VIA        MD0040PA00X+007290Y+139360               S0      
317GND              VIA        MD0040PA00X+007300Y+149120               S0      
317GND              VIA        MD0040PA00X+007350Y+014600               S0      
317GND              VIA        MD0040PA00X+007400Y+113200               S0      
317GND              VIA        MD0040PA00X+007400Y+004500               S0      
317GND              VIA        MD0040PA00X+007410Y+066940               S0      
317GND              VIA        MD0040PA00X+007450Y+146180               S0      
317GND              VIA        MD0040PA00X+007490Y+140880               S0      
317GND              VIA        MD0040PA00X+007494Y+053098               S0      
317GND              VIA        MD0040PA00X+000750Y+137650               S0      
317GND              VIA        MD0040PA00X+000750Y+164020               S0      
317GND              VIA        MD0040PA00X+007550Y+093650               S0      
317GND              VIA        MD0040PA00X+007560Y+142030               S0      
317GND              VIA        MD0040PA00X+007620Y+143070               S0      
317GND              VIA        MD0040PA00X+007640Y+099910               S0      
317GND              VIA        MD0040PA00X+007650Y+092700               S0      
317GND              VIA        MD0040PA00X+007700Y+144900               S0      
317GND              VIA        MD0040PA00X+007700Y+086300               S0      
317GND              VIA        MD0040PA00X+007700Y+087150               S0      
317GND              VIA        MD0040PA00X+007729Y+112973               S0      
317GND              VIA        MD0040PA00X+007750Y+090700               S0      
317GND              VIA        MD0040PA00X+007750Y+091700               S0      
317GND              VIA        MD0040PA00X+007760Y+084910               S0      
317GND              VIA        MD0040PA00X+007800Y+087850               S0      
317GND              VIA        MD0040PA00X+007830Y+083260               S0      
317GND              VIA        MD0040PA00X+007830Y+089390               S0      
317GND              VIA        MD0040PA00X+007900Y+143640               S0      
317GND              VIA        MD0040PA00X+007900Y+085700               S0      
317GND              VIA        MD0040PA00X+007904Y+114411               S0      
317GND              VIA        MD0040PA00X+007912Y+056570               S0      
317GND              VIA        MD0040PA00X+007946Y+057876               S0      
317GND              VIA        MD0040PA00X+000800Y+136800               S0      
317GND              VIA        MD0040PA00X+000800Y+067800               S0      
317GND              VIA        MD0040PA00X+008150Y+138200               S0      
317GND              VIA        MD0040PA00X+008150Y+140400               S0      
317GND              VIA        MD0040PA00X+008150Y+141650               S0      
317GND              VIA        MD0040PA00X+008150Y+083750               S0      
317GND              VIA        MD0040PA00X+008150Y+094000               S0      
317GND              VIA        MD0040PA00X+008200Y+080650               S0      
317GND              VIA        MD0040PA00X+008250Y+081400               S0      
317GND              VIA        MD0040PA00X+008340Y+087860               S0      
317GND              VIA        MD0040PA00X+008380Y+136590               S0      
317GND              VIA        MD0040PA00X+008380Y+139190               S0      
317GND              VIA        MD0040PA00X+008400Y+135200               S0      
317GND              VIA        MD0040PA00X+000850Y+123700               S0      
317GND              VIA        MD0040PA00X+000859Y+000650               S0      
317GND              VIA        MD0040PA00X+008500Y+004500               S0      
317GND              VIA        MD0040PA00X+008550Y+090300               S0      
317GND              VIA        MD0040PA00X+008550Y+091500               S0      
317GND              VIA        MD0040PA00X+008600Y+015200               S0      
317GND              VIA        MD0040PA00X+008650Y+093200               S0      
317GND              VIA        MD0040PA00X+008700Y+083950               S0      
317GND              VIA        MD0040PA00X+008700Y+099750               S0      
317GND              VIA        MD0040PA00X+008720Y+143190               S0      
317GND              VIA        MD0040PA00X+008730Y+143600               S0      
317GND              VIA        MD0040PA00X+008731Y+067680               S0      
317GND              VIA        MD0040PA00X+008760Y+058130               S0      
317GND              VIA        MD0040PA00X+008770Y+144650               S0      
317GND              VIA        MD0040PA00X+008850Y+094050               S0      
317GND              VIA        MD0040PA00X+008970Y+140970               S0      
317GND              VIA        MD0040PA00X+009000Y+089300               S0      
317GND              VIA        MD0040PA00X+009050Y+083150               S0      
317GND              VIA        MD0040PA00X+009080Y+133120               S0      
317GND              VIA        MD0040PA00X+009150Y+120000               S0      
317GND              VIA        MD0040PA00X+009150Y+122900               S0      
317GND              VIA        MD0040PA00X+009150Y+131450               S0      
317GND              VIA        MD0040PA00X+009200Y+121450               S0      
317GND              VIA        MD0040PA00X+009200Y+124150               S0      
317GND              VIA        MD0040PA00X+009200Y+125400               S0      
317GND              VIA        MD0040PA00X+009200Y+129550               S0      
317GND              VIA        MD0040PA00X+009300Y+092550               S0      
317GND              VIA        MD0040PA00X+009350Y+148270               S0      
317GND              VIA        MD0040PA00X+009360Y+140710               S0      
317GND              VIA        MD0040PA00X+009380Y+135390               S0      
317GND              VIA        MD0040PA00X+009380Y+137990               S0      
317GND              VIA        MD0040PA00X+009380Y+139320               S0      
317GND              VIA        MD0040PA00X+009400Y+118900               S0      
317GND              VIA        MD0040PA00X+009400Y+134000               S0      
317GND              VIA        MD0040PA00X+009400Y+136600               S0      
317GND              VIA        MD0040PA00X+009400Y+142780               S0      
317GND              VIA        MD0040PA00X+009400Y+091050               S0      
317GND              VIA        MD0040PA00X+000950Y+080400               S0      
317GND              VIA        MD0040PA00X+009500Y+012500               S0      
317GND              VIA        MD0040PA00X+009500Y+013400               S0      
317GND              VIA        MD0040PA00X+009500Y+014300               S0      
317GND              VIA        MD0040PA00X+009500Y+015500               S0      
317GND              VIA        MD0040PA00X+009500Y+004500               S0      
317GND              VIA        MD0040PA00X+009550Y+146800               S0      
317GND              VIA        MD0040PA00X+009550Y+084150               S0      
317GND              VIA        MD0040PA00X+009550Y+099900               S0      
317GND              VIA        MD0040PA00X+009605Y+090325               S0      
317GND              VIA        MD0040PA00X+009650Y+091650               S0      
317GND              VIA        MD0040PA00X+009700Y+150310               S0      
317GND              VIA        MD0040PA00X+009750Y+141200               S0      
317GND              VIA        MD0040PA00X+009780Y+132790               S0      
317GND              VIA        MD0040PA00X+009800Y+128200               S0      
317GND              VIA        MD0040PA00X+009800Y+042650               S0      
317GND              VIA        MD0040PA00X+009800Y+067433               S0      
317GND              VIA        MD0040PA00X+009900Y+126550               S0      
317GND              VIA        MD0040PA00X+009900Y+095300               S0      
317GND              VIA        MD0040PA00X+009900Y+069487               S0      
317GND              VIA        MD0040PA00X+009917Y+148579               S0      
317GND              VIA        MD0040PA00X+009950Y+129400               S0      
317GND              VIA        MD0040PA00X+009950Y+131000               S0      
317GND              VIA        MD0040PA00X+011302Y+145208               S0      
317GND              VIA        MD0040PA00X+011702Y+145200               S0      
317GND              VIA        MD0040PA00X+011712Y+144800               S0      
317GND              VIA        MD0040PA00X+011720Y+145607               S0      
317GND              VIA        MD0040PA00X+012134Y+145202               S0      
317GND              VIA        MD0040PA00X+013800Y+182400               S0      
317GND              VIA        MD0040PA00X+013850Y+172750               S0      
317GND              VIA        MD0040PA00X+013850Y+183950               S0      
317GND              VIA        MD0040PA00X+013900Y+169650               S0      
317GND              VIA        MD0040PA00X+013900Y+171250               S0      
317GND              VIA        MD0040PA00X+013900Y+180050               S0      
317GND              VIA        MD0040PA00X+013900Y+185100               S0      
317GND              VIA        MD0040PA00X+015150Y+185111               S0      
317GND              VIA        MD0040PA00X+015200Y+169711               S0      
317GND              VIA        MD0040PA00X+015200Y+171061               S0      
317GND              VIA        MD0040PA00X+015200Y+172561               S0      
317GND              VIA        MD0040PA00X+015200Y+179011               S0      
317GND              VIA        MD0040PA00X+015250Y+177111               S0      
317GND              VIA        MD0040PA00X+015550Y+179850               S0      
317GND              VIA        MD0040PA00X+015650Y+178200               S0      
317GND              VIA        MD0040PA00X+015850Y+170500               S0      
317GND              VIA        MD0040PA00X+015850Y+171650               S0      
317GND              VIA        MD0040PA00X+016150Y+185250               S0      
317GND              VIA        MD0040PA00X+016200Y+179000               S0      
317GND              VIA        MD0040PA00X+016250Y+177300               S0      
317GND              VIA        MD0040PA00X+016300Y+169700               S0      
317GND              VIA        MD0040PA00X+016650Y+179800               S0      
317GND              VIA        MD0040PA00X+016750Y+171600               S0      
317GND              VIA        MD0040PA00X+016850Y+170500               S0      
317GND              VIA        MD0040PA00X+016900Y+178150               S0      
317GND              VIA        MD0040PA00X+017277Y+179011               S0      
317GND              VIA        MD0040PA00X+017300Y+185261               S0      
317GND              VIA        MD0040PA00X+017327Y+177600               S0      
317GND              VIA        MD0040PA00X+017427Y+169711               S0      
317GND              VIA        MD0040PA00X+017900Y+179850               S0      
317GND              VIA        MD0040PA00X+018150Y+171650               S0      
317GND              VIA        MD0040PA00X+018200Y+170400               S0      
317GND              VIA        MD0040PA00X+018200Y+172600               S0      
317GND              VIA        MD0040PA00X+018310Y+183830               S0      
317GND              VIA        MD0040PA00X+018360Y+176510               S0      
317GND              VIA        MD0040PA00X+018450Y+169650               S0      
317GND              VIA        MD0040PA00X+018500Y+173850               S0      
317GND              VIA        MD0040PA00X+018500Y+185250               S0      
317GND              VIA        MD0040PA00X+018550Y+180450               S0      
317GND              VIA        MD0040PA00X+018600Y+179000               S0      
317P3V3                         D0040PA01X+008400Y+085720               S0      
317P3V3                         D0040PA01X+015854Y+060408               S0      
327P3V3                         D0040PA01X+006688Y+068111               S0      
317P3V3                         D0040PA01X+018037Y+064237               S0      
317P3V3                         D0040PA01X+003280Y+027230               S0      
317P3V3                         D0040PA01X+011050Y+093630               S0      
317P3V3                         D0040PA01X+012990Y+098690               S0      
317P3V3                         D0040PA01X+018202Y+061354               S0      
327P3V3                         D0040PA01X+010450Y+093351               S0      
317P3V3                         D0040PA01X+011190Y+140820               S0      
317P3V3                         D0040PA01X+002020Y+169280               S0      
317P3V3                         D0040PA01X+008750Y+087285               S0      
317P3V3                         D0040PA01X+010710Y+099080               S0      
317P3V3                         D0040PA01X+006720Y+070540               S0      
317P3V3                         D0040PA01X+016350Y+099770               S0      
317P3V3                         D0040PA01X+008400Y+085290               S0      
317P3V3                         D0040PA01X+005780Y+021700               S0      
317P3V3                         D0040PA01X+009307Y+059407               S0      
317P3V3                         D0040PA01X+009230Y+087285               S0      
327P3V3                         D0040PA01X+011396Y+098520               S0      
317P3V3                         D0040PA01X+004340Y+089270               S0      
317P3V3                         D0040PA01X+015210Y+100320               S0      
317P3V3                         D0040PA01X+006030Y+028000               S0      
317P3V3                         D0040PA01X+002410Y+068530               S0      
317P3V3                         D0040PA01X+008400Y+084850               S0      
317P3V3                         D0040PA01X+015700Y+094580               S0      
327P3V3                         D0040PA01X+013734Y+098170               S0      
327P3V3                         D0040PA01X+017137Y+063482               S0      
317P3V3                         D0040PA01X+006140Y+067680               S0      
317P3V3                         D0040PA01X+010750Y+140810               S0      
317P3V3                         D0040PA01X+007220Y+070540               S0      
317P3V3                         D0040PA01X+008400Y+084410               S0      
317P3V3                         D0040PA01X+001860Y+164430               S0      
317P3V3                         D0040PA01X+014500Y+094580               S0      
327P3V3                         D0040PA01X+005825Y+069056               S0      
327P3V3                         D0040PA01X+010082Y+086850               S0      
317P3V3                         D0040PA01X+007054Y+068831               S0      
317P3V3                         D0040PA01X+013080Y+098140               S0      
317P3V3                         D0040PA01X+011800Y+142080               S0      
317P3V3                         D0040PA01X+012907Y+067869               S0      
317P3V3                         D0040PA01X+006100Y+023660               S0      
317P3V3                         D0040PA01X+012347Y+067869               S0      
317P3V3                         D0040PA01X+015300Y+094580               S0      
317P3V3                         D0040PA01X+003270Y+025690               S0      
327P3V3                         D0040PA01X+004275Y+069056               S0      
317P3V3                         D0040PA01X+013777Y+066207               S0      
317P3V3                         D0040PA01X+002770Y+110600               S0      
317P3V3                         D0040PA01X+002890Y+068530               S0      
317P3V3                         D0040PA01X+006260Y+024580               S0      
317P3V3                         D0040PA01X+010500Y+142030               S0      
317P3V3                         D0040PA01X+015950Y+099770               S0      
317P3V3                         D0040PA01X+007856Y+069047               S0      
317P3V3                         D0040PA01X+011730Y+093630               S0      
317P3V3                         D0040PA01X+005740Y+067680               S0      
317P3V3                         D0040PA01X+006160Y+020790               S0      
317P3V3                         D0040PA01X+002910Y+032130               S0      
317P3V3                         D0040PA01X+008400Y+086150               S0      
317P3V3                         D0040PA01X+014790Y+100310               S0      
317P3V3                         D0040PA01X+008070Y+068640               S0      
317P3V3                         D0040PA01X+012167Y+093636               S0      
317P3V3                         D0040PA01X+008400Y+086570               S0      
327P3V3                         D0040PA01X+011331Y+067742               S0      
317P3V3                         D0040PA01X+014380Y+100320               S0      
317P3V3                         D0040PA01X+014900Y+094580               S0      
317P3V3                         D0040PA01X+018047Y+063497               S0      
317P3V3                         D0040PA01X+009520Y+066570               S0      
317P3V3                         D0040PA01X+006564Y+068831               S0      
317P3V3                         D0040PA01X+006300Y+026770               S0      
317P3V3                         D0040PA01X+010710Y+098600               S0      
317P3V3             VIA        MD0040PA04X+005200Y+086750               S0      
317P3V3             VIA        MD0040PA04X+005680Y+069100               S0      
317P3V3             VIA        MD0040PA04X+005680Y+083100               S0      
317P3V3             VIA        MD0040PA00X+001330Y+164430               S0      
317P3V3             VIA        MD0040PA00X+001330Y+168960               S0      
317P3V3             VIA        MD0040PA00X+002550Y+032120               S0      
317P3V3             VIA        MD0040PA00X+002645Y+027475               S0      
317P3V3             VIA        MD0040PA00X+004272Y+023399               S0      
317P3V3             VIA        MD0040PA00X+004960Y+088940               S0      
317P3V3             VIA        MD0040PA00X+005300Y+067350               S0      
317P3V3             VIA        MD0040PA00X+005440Y+021700               S0      
317P3V3             VIA        MD0040PA00X+005742Y+023297               S0      
317P3V3             VIA        MD0040PA00X+005750Y+084450               S0      
317P3V3             VIA        MD0040PA00X+005768Y+069764               S0      
317P3V3             VIA        MD0040PA00X+006500Y+023540               S0      
317P3V3             VIA        MD0040PA00X+006500Y+024150               S0      
317P3V3             VIA        MD0040PA00X+006520Y+020785               S0      
317P3V3             VIA        MD0040PA00X+006800Y+026800               S0      
317P3V3             VIA        MD0040PA00X+007060Y+025050               S0      
317P3V3             VIA        MD0040PA00X+010550Y+141500               S0      
317P3V3             VIA        MD0040PA00X+002805Y+025695               S0      
317P3V3             VIA        MD0040PA00X+003930Y+110580               S0      
317P3V3             VIA        MD0040PA00X+004100Y+093190               S0      
317P3V3             VIA        MD0040PA00X+005671Y+068107               S0      
317P3V3             VIA        MD0040PA00X+006450Y+116570               S0      
317P3V3             VIA        MD0040PA00X+008900Y+116740               S0      
327P12VU                        D0040PA01X+008343Y+054475               S0      
327P12VU                        D0040PA01X+004770Y+039780               S0      
317P12VU                        D0040PA00X+008071Y+028693               S0      
317P12VU                        D0040PA00X+009071Y+028693               S0      
317P12VU                        D0040PA00X+010071Y+028693               S0      
317P12VU                        D0040PA00X+011071Y+028693               S0      
317P12VU                        D0040PA00X+008071Y+027693               S0      
317P12VU                        D0040PA00X+009071Y+027693               S0      
317P12VU                        D0040PA00X+010071Y+027693               S0      
317P12VU                        D0040PA00X+011071Y+027693               S0      
317P12VU                        D0040PA00X+008071Y+026693               S0      
317P12VU                        D0040PA00X+009071Y+026693               S0      
317P12VU                        D0040PA00X+010071Y+026693               S0      
317P12VU                        D0040PA00X+011071Y+026693               S0      
317P12VU                        D0040PA00X+008071Y+025693               S0      
317P12VU                        D0040PA00X+009071Y+025693               S0      
317P12VU                        D0040PA00X+010071Y+025693               S0      
317P12VU                        D0040PA00X+011071Y+025693               S0      
327P12VU                        D0040PA01X+004770Y+041830               S0      
327P12VU                        D0040PA01X+006900Y+044000               S0      
327P12VU                        D0040PA01X+007400Y+044000               S0      
327P12VU                        D0040PA01X+007900Y+044000               S0      
327P12VU                        D0040PA01X+008110Y+039850               S0      
327P12VU                        D0040PA01X+008110Y+041900               S0      
327P12VU                        D0040PA01X+009650Y+043950               S0      
327P12VU                        D0040PA01X+010150Y+043950               S0      
327P12VU                        D0040PA01X+010650Y+043950               S0      
317P12VU                        D0040PA01X+007370Y+053990               S0      
327P12VU                        D0040PA01X+006964Y+036190               S0      
317P12VU                        D0040PA01X+012890Y+058520               S0      
317P12VU                        D0040PA01X+004000Y+029430               S0      
317P12VU            VIA        MD0040PA01X+006170Y+042190               S0      
317P12VU            VIA        MD0040PA01X+006240Y+043060               S0      
317P12VU            VIA        MD0040PA01X+006290Y+041290               S0      
317P12VU            VIA        MD0040PA01X+006320Y+038510               S0      
317P12VU            VIA        MD0040PA00X+012890Y+058050               S0      
317P12VU            VIA        MD0040PA00X+007780Y+054030               S0      
317P12VU            VIA        MD0040PA00X+010200Y+031200               S0      
317P12VU            VIA        MD0040PA00X+010400Y+030400               S0      
317P12VU            VIA        MD0040PA00X+010600Y+029600               S0      
317P12VU            VIA        MD0040PA00X+011400Y+029600               S0      
317P12VU            VIA        MD0040PA00X+005800Y+039000               S0      
317P12VU            VIA        MD0040PA00X+005800Y+040000               S0      
317P12VU            VIA        MD0040PA00X+005800Y+040800               S0      
317P12VU            VIA        MD0040PA00X+005800Y+041750               S0      
317P12VU            VIA        MD0040PA00X+005800Y+042600               S0      
317P12VU            VIA        MD0040PA00X+005810Y+043190               S0      
317P12VU            VIA        MD0040PA00X+006310Y+043454               S0      
317P12VU            VIA        MD0040PA00X+006600Y+039000               S0      
317P12VU            VIA        MD0040PA00X+006600Y+040000               S0      
317P12VU            VIA        MD0040PA00X+006600Y+040800               S0      
317P12VU            VIA        MD0040PA00X+006600Y+041800               S0      
317P12VU            VIA        MD0040PA00X+006600Y+042600               S0      
317P12VU            VIA        MD0040PA00X+006800Y+028600               S0      
317P12VU            VIA        MD0040PA00X+006800Y+029600               S0      
317P12VU            VIA        MD0040PA00X+006800Y+030400               S0      
317P12VU            VIA        MD0040PA00X+006800Y+031200               S0      
317P12VU            VIA        MD0040PA00X+006800Y+032000               S0      
317P12VU            VIA        MD0040PA00X+006850Y+043430               S0      
317P12VU            VIA        MD0040PA00X+007370Y+042300               S0      
317P12VU            VIA        MD0040PA00X+007400Y+039000               S0      
317P12VU            VIA        MD0040PA00X+007400Y+040000               S0      
317P12VU            VIA        MD0040PA00X+007400Y+040800               S0      
317P12VU            VIA        MD0040PA00X+007400Y+041800               S0      
317P12VU            VIA        MD0040PA00X+007600Y+029600               S0      
317P12VU            VIA        MD0040PA00X+008100Y+041050               S0      
317P12VU            VIA        MD0040PA00X+008450Y+043300               S0      
317P12VU            VIA        MD0040PA00X+008600Y+029600               S0      
317P12VU            VIA        MD0040PA00X+008640Y+041050               S0      
317P12VU            VIA        MD0040PA00X+008850Y+042650               S0      
317P12VU            VIA        MD0040PA00X+009190Y+041050               S0      
317P12VU            VIA        MD0040PA00X+009400Y+030400               S0      
317P12VU            VIA        MD0040PA00X+009400Y+031200               S0      
317P12VU            VIA        MD0040PA00X+009400Y+032000               S0      
317P12VU            VIA        MD0040PA00X+009600Y+029600               S0      
327P12VL                        D0040PA01X+016040Y+035670               S0      
327P12VL                        D0040PA01X+016060Y+037690               S0      
327P12VL                        D0040PA01X+016900Y+043950               S0      
327P12VL                        D0040PA01X+017400Y+043950               S0      
327P12VL                        D0040PA01X+017900Y+043950               S0      
327P12VL                        D0040PA01X+014723Y+054295               S0      
317P12VL                        D0040PA01X+013678Y+053967               S0      
317P12VL                        D0040PA01X+011680Y+058520               S0      
327P12VL                        D0040PA01X+014047Y+036180               S0      
317P12VL                        D0040PA00X+014961Y+028693               S0      
317P12VL                        D0040PA00X+015961Y+028693               S0      
317P12VL                        D0040PA00X+016961Y+028693               S0      
317P12VL                        D0040PA00X+017961Y+028693               S0      
317P12VL                        D0040PA00X+014961Y+027693               S0      
317P12VL                        D0040PA00X+015961Y+027693               S0      
317P12VL                        D0040PA00X+016961Y+027693               S0      
317P12VL                        D0040PA00X+017961Y+027693               S0      
317P12VL                        D0040PA00X+014961Y+026693               S0      
317P12VL                        D0040PA00X+015961Y+026693               S0      
317P12VL                        D0040PA00X+016961Y+026693               S0      
317P12VL                        D0040PA00X+017961Y+026693               S0      
317P12VL                        D0040PA00X+014961Y+025693               S0      
317P12VL                        D0040PA00X+015961Y+025693               S0      
317P12VL                        D0040PA00X+016961Y+025693               S0      
317P12VL                        D0040PA00X+017961Y+025693               S0      
317P12VL                        D0040PA01X+011690Y+038010               S0      
327P12VL                        D0040PA01X+014100Y+043950               S0      
327P12VL                        D0040PA01X+014600Y+043950               S0      
327P12VL                        D0040PA01X+015100Y+043950               S0      
327P12VL                        D0040PA01X+016050Y+041840               S0      
327P12VL                        D0040PA01X+016050Y+039790               S0      
317P12VL            VIA        MD0040PA01X+012250Y+042900               S0      
317P12VL            VIA        MD0040PA01X+012510Y+040890               S0      
317P12VL            VIA        MD0040PA01X+014340Y+040820               S0      
317P12VL            VIA        MD0040PA00X+012230Y+057500               S0      
317P12VL            VIA        MD0040PA00X+013250Y+053962               S0      
317P12VL            VIA        MD0040PA00X+013550Y+044100               S0      
317P12VL            VIA        MD0040PA00X+011800Y+038600               S0      
317P12VL            VIA        MD0040PA00X+011800Y+039600               S0      
317P12VL            VIA        MD0040PA00X+011800Y+040400               S0      
317P12VL            VIA        MD0040PA00X+011800Y+041400               S0      
317P12VL            VIA        MD0040PA00X+011800Y+042400               S0      
317P12VL            VIA        MD0040PA00X+013000Y+043200               S0      
317P12VL            VIA        MD0040PA00X+013400Y+038600               S0      
317P12VL            VIA        MD0040PA00X+013400Y+039600               S0      
317P12VL            VIA        MD0040PA00X+013400Y+040450               S0      
317P12VL            VIA        MD0040PA00X+013400Y+041400               S0      
317P12VL            VIA        MD0040PA00X+013400Y+042400               S0      
317P12VL            VIA        MD0040PA00X+014200Y+029100               S0      
317P12VL            VIA        MD0040PA00X+014200Y+043200               S0      
317P12VL            VIA        MD0040PA00X+014330Y+034340               S0      
317P12VL            VIA        MD0040PA00X+014340Y+031870               S0      
317P12VL            VIA        MD0040PA00X+014550Y+042700               S0      
317P12VL            VIA        MD0040PA00X+015000Y+038600               S0      
317P12VL            VIA        MD0040PA00X+015000Y+039600               S0      
317P12VL            VIA        MD0040PA00X+015000Y+040400               S0      
317P12VL            VIA        MD0040PA00X+015000Y+041400               S0      
317P12VL            VIA        MD0040PA00X+015000Y+042400               S0      
317P12VL            VIA        MD0040PA00X+015130Y+029820               S0      
317P12VL            VIA        MD0040PA00X+016200Y+029600               S0      
317P12VL            VIA        MD0040PA00X+016200Y+043200               S0      
317P12VL            VIA        MD0040PA00X+016400Y+031600               S0      
317P12VL            VIA        MD0040PA00X+016600Y+030200               S0      
317P12VL            VIA        MD0040PA00X+017200Y+029600               S0      
317P12VL            VIA        MD0040PA00X+017200Y+031000               S0      
317P12VL            VIA        MD0040PA00X+017400Y+031600               S0      
317P12VL            VIA        MD0040PA00X+017450Y+043200               S0      
317P12VL            VIA        MD0040PA00X+017600Y+030200               S0      
317P12VL            VIA        MD0040PA00X+018200Y+029600               S0      
317P12VL            VIA        MD0040PA00X+018200Y+031000               S0      
317P12VL            VIA        MD0040PA00X+018400Y+030300               S0      
317P12V_AUX                     D0040PA01X+008430Y+148400               S0      
317P12V_AUX                     D0040PA01X+009646Y+177343               S0      
317P12V_AUX                     D0040PA01X+018230Y+164800               S0      
327P12V_AUX                     D0040PA01X+006064Y+168050               S0      
327P12V_AUX                     D0040PA01X+013540Y+073005               S0      
327P12V_AUX                     D0040PA01X+015775Y+161970               S0      
317P12V_AUX                     D0040PA01X+018230Y+165270               S0      
327P12V_AUX                     D0040PA01X+018070Y+164100               S0      
317P12V_AUX                     D0040PA01X+008350Y+146520               S0      
317P12V_AUX                     D0040PA01X+015233Y+142768               S0      
317P12V_AUX                     D0040PA01X+015210Y+142340               S0      
327P12V_AUX                     D0040PA01X+010175Y+161970               S0      
317P12V_AUX                     D0040PA01X+014360Y+145330               S0      
317P12V_AUX                     D0040PA01X+015210Y+141500               S0      
327P12V_AUX                     D0040PA01X+013025Y+161970               S0      
317P12V_AUX                     D0040PA01X+015210Y+141920               S0      
317P12V_AUX                     D0040PA01X+012490Y+072820               S0      
327P12V_AUX                     D0040PA01X+016700Y+146530               S0      
327P12V_AUX                     D0040PA01X+007125Y+161970               S0      
317P12V_AUX                     D0040PA01X+017770Y+062430               S0      
317P12V_AUX                     D0040PA01X+010750Y+149020               S0      
317P12V_AUX                     D0040PA00X+009646Y+174784               S0      
317P12V_AUX                     D0040PA00X+009646Y+182303               S0      
317P12V_AUX         VIA        MD0040PA04X+007100Y+186450               S0      
317P12V_AUX         VIA        MD0040PA04X+007650Y+149850               S0      
317P12V_AUX         VIA        MD0040PA01X+013650Y+165100               S0      
317P12V_AUX         VIA        MD0040PA01X+005950Y+162750               S0      
317P12V_AUX         VIA        MD0040PA01X+006150Y+171650               S0      
317P12V_AUX         VIA        MD0040PA01X+006230Y+164130               S0      
317P12V_AUX         VIA        MD0040PA01X+008400Y+186960               S0      
317P12V_AUX         VIA        MD0040PA00X+011275Y+149125               S0      
317P12V_AUX         VIA        MD0040PA00X+013990Y+141510               S0      
317P12V_AUX         VIA        MD0040PA00X+015850Y+146650               S0      
317P12V_AUX         VIA        MD0040PA00X+015860Y+075260               S0      
317P12V_AUX         VIA        MD0040PA00X+017420Y+062820               S0      
317P12V_AUX         VIA        MD0040PA00X+010300Y+168500               S0      
317P12V_AUX         VIA        MD0040PA00X+010600Y+163400               S0      
317P12V_AUX         VIA        MD0040PA00X+010650Y+186250               S0      
317P12V_AUX         VIA        MD0040PA00X+010700Y+165950               S0      
317P12V_AUX         VIA        MD0040PA00X+010700Y+166900               S0      
317P12V_AUX         VIA        MD0040PA00X+010750Y+167900               S0      
317P12V_AUX         VIA        MD0040PA00X+010800Y+164600               S0      
317P12V_AUX         VIA        MD0040PA00X+011250Y+168500               S0      
317P12V_AUX         VIA        MD0040PA00X+011450Y+186250               S0      
317P12V_AUX         VIA        MD0040PA00X+011700Y+163350               S0      
317P12V_AUX         VIA        MD0040PA00X+011750Y+165950               S0      
317P12V_AUX         VIA        MD0040PA00X+011750Y+166900               S0      
317P12V_AUX         VIA        MD0040PA00X+011750Y+167900               S0      
317P12V_AUX         VIA        MD0040PA00X+011800Y+164600               S0      
317P12V_AUX         VIA        MD0040PA00X+012200Y+168550               S0      
317P12V_AUX         VIA        MD0040PA00X+012250Y+186250               S0      
317P12V_AUX         VIA        MD0040PA00X+012500Y+167900               S0      
317P12V_AUX         VIA        MD0040PA00X+012700Y+164600               S0      
317P12V_AUX         VIA        MD0040PA00X+012750Y+163300               S0      
317P12V_AUX         VIA        MD0040PA00X+012750Y+165950               S0      
317P12V_AUX         VIA        MD0040PA00X+012750Y+166900               S0      
317P12V_AUX         VIA        MD0040PA00X+013750Y+165950               S0      
317P12V_AUX         VIA        MD0040PA00X+013800Y+163400               S0      
317P12V_AUX         VIA        MD0040PA00X+013800Y+164600               S0      
317P12V_AUX         VIA        MD0040PA00X+014800Y+164600               S0      
317P12V_AUX         VIA        MD0040PA00X+014850Y+166000               S0      
317P12V_AUX         VIA        MD0040PA00X+014900Y+163250               S0      
317P12V_AUX         VIA        MD0040PA00X+015250Y+145600               S0      
317P12V_AUX         VIA        MD0040PA00X+015800Y+164600               S0      
317P12V_AUX         VIA        MD0040PA00X+015900Y+163250               S0      
317P12V_AUX         VIA        MD0040PA00X+015900Y+165950               S0      
317P12V_AUX         VIA        MD0040PA00X+016600Y+164600               S0      
317P12V_AUX         VIA        MD0040PA00X+016750Y+163250               S0      
317P12V_AUX         VIA        MD0040PA00X+017000Y+165950               S0      
317P12V_AUX         VIA        MD0040PA00X+017600Y+163200               S0      
317P12V_AUX         VIA        MD0040PA00X+017600Y+164600               S0      
317P12V_AUX         VIA        MD0040PA00X+017800Y+165950               S0      
317P12V_AUX         VIA        MD0040PA00X+005350Y+165900               S0      
317P12V_AUX         VIA        MD0040PA00X+005400Y+164650               S0      
317P12V_AUX         VIA        MD0040PA00X+005550Y+172350               S0      
317P12V_AUX         VIA        MD0040PA00X+005550Y+173550               S0      
317P12V_AUX         VIA        MD0040PA00X+005600Y+169500               S0      
317P12V_AUX         VIA        MD0040PA00X+005600Y+170450               S0      
317P12V_AUX         VIA        MD0040PA00X+005600Y+171250               S0      
317P12V_AUX         VIA        MD0040PA00X+005750Y+163450               S0      
317P12V_AUX         VIA        MD0040PA00X+005950Y+166700               S0      
317P12V_AUX         VIA        MD0040PA00X+006000Y+173000               S0      
317P12V_AUX         VIA        MD0040PA00X+006250Y+169150               S0      
317P12V_AUX         VIA        MD0040PA00X+006250Y+170000               S0      
317P12V_AUX         VIA        MD0040PA00X+006250Y+170900               S0      
317P12V_AUX         VIA        MD0040PA00X+006350Y+185600               S0      
317P12V_AUX         VIA        MD0040PA00X+006350Y+186300               S0      
317P12V_AUX         VIA        MD0040PA00X+006400Y+163400               S0      
317P12V_AUX         VIA        MD0040PA00X+006400Y+183400               S0      
317P12V_AUX         VIA        MD0040PA00X+006400Y+184450               S0      
317P12V_AUX         VIA        MD0040PA00X+006450Y+164600               S0      
317P12V_AUX         VIA        MD0040PA00X+006450Y+165850               S0      
317P12V_AUX         VIA        MD0040PA00X+006450Y+175850               S0      
317P12V_AUX         VIA        MD0040PA00X+006450Y+180150               S0      
317P12V_AUX         VIA        MD0040PA00X+006450Y+181200               S0      
317P12V_AUX         VIA        MD0040PA00X+006450Y+182150               S0      
317P12V_AUX         VIA        MD0040PA00X+006500Y+172400               S0      
317P12V_AUX         VIA        MD0040PA00X+006500Y+173500               S0      
317P12V_AUX         VIA        MD0040PA00X+006500Y+174250               S0      
317P12V_AUX         VIA        MD0040PA00X+006500Y+174900               S0      
317P12V_AUX         VIA        MD0040PA00X+006500Y+176800               S0      
317P12V_AUX         VIA        MD0040PA00X+006500Y+179000               S0      
317P12V_AUX         VIA        MD0040PA00X+006900Y+168450               S0      
317P12V_AUX         VIA        MD0040PA00X+007000Y+166800               S0      
317P12V_AUX         VIA        MD0040PA00X+007550Y+165950               S0      
317P12V_AUX         VIA        MD0040PA00X+007550Y+167900               S0      
317P12V_AUX         VIA        MD0040PA00X+007600Y+163400               S0      
317P12V_AUX         VIA        MD0040PA00X+007600Y+164600               S0      
317P12V_AUX         VIA        MD0040PA00X+008050Y+168450               S0      
317P12V_AUX         VIA        MD0040PA00X+008350Y+146950               S0      
317P12V_AUX         VIA        MD0040PA00X+008500Y+149000               S0      
317P12V_AUX         VIA        MD0040PA00X+008600Y+163400               S0      
317P12V_AUX         VIA        MD0040PA00X+008600Y+164600               S0      
317P12V_AUX         VIA        MD0040PA00X+008600Y+165950               S0      
317P12V_AUX         VIA        MD0040PA00X+008600Y+166900               S0      
317P12V_AUX         VIA        MD0040PA00X+008600Y+167900               S0      
317P12V_AUX         VIA        MD0040PA00X+009100Y+168500               S0      
317P12V_AUX         VIA        MD0040PA00X+009600Y+164600               S0      
317P12V_AUX         VIA        MD0040PA00X+009650Y+163400               S0      
317P12V_AUX         VIA        MD0040PA00X+009700Y+165950               S0      
317P12V_AUX         VIA        MD0040PA00X+009700Y+166900               S0      
317P12V_AUX         VIA        MD0040PA00X+009750Y+167950               S0      
317P12V_AUX         VIA        MD0040PA00X+009950Y+186250               S0      
317P12V_AUX         VIA        MD0040PA00X+010777Y+178911               S0      
317P12V_AUX         VIA        MD0040PA00X+010827Y+177730               S0      
317P12V_AUX         VIA        MD0040PA00X+010850Y+172700               S0      
317P12V_AUX         VIA        MD0040PA00X+010850Y+185161               S0      
317P12V_AUX         VIA        MD0040PA00X+010950Y+169900               S0      
317P12V_AUX         VIA        MD0040PA00X+010950Y+171950               S0      
317P12V_AUX         VIA        MD0040PA00X+011000Y+170950               S0      
317P12V_AUX         VIA        MD0040PA00X+011050Y+180100               S0      
317P12V_AUX         VIA        MD0040PA00X+011150Y+176850               S0      
317P12V_AUX         VIA        MD0040PA00X+011400Y+184350               S0      
317P12V_AUX         VIA        MD0040PA00X+011750Y+173200               S0      
317P12V_AUX         VIA        MD0040PA00X+011950Y+169661               S0      
317P12V_AUX         VIA        MD0040PA00X+011950Y+171011               S0      
317P12V_AUX         VIA        MD0040PA00X+011950Y+172511               S0      
317P12V_AUX         VIA        MD0040PA00X+011950Y+174711               S0      
317P12V_AUX         VIA        MD0040PA00X+011950Y+176000               S0      
317P12V_AUX         VIA        MD0040PA00X+011950Y+179650               S0      
317P12V_AUX         VIA        MD0040PA00X+012000Y+181150               S0      
317P12V_AUX         VIA        MD0040PA00X+012050Y+183650               S0      
317P12V_AUX         VIA        MD0040PA00X+012050Y+185050               S0      
317P12V_AUX         VIA        MD0040PA00X+007150Y+176000               S0      
317P12V_AUX         VIA        MD0040PA00X+007200Y+179800               S0      
317P12V_AUX         VIA        MD0040PA00X+007250Y+169900               S0      
317P12V_AUX         VIA        MD0040PA00X+007250Y+171700               S0      
317P12V_AUX         VIA        MD0040PA00X+007250Y+173300               S0      
317P12V_AUX         VIA        MD0040PA00X+007250Y+183000               S0      
317P12V_AUX         VIA        MD0040PA00X+007300Y+181300               S0      
317P12V_AUX         VIA        MD0040PA00X+007300Y+184700               S0      
317P12V_AUX         VIA        MD0040PA00X+007550Y+183850               S0      
317P12V_AUX         VIA        MD0040PA00X+007900Y+176650               S0      
317P12V_AUX         VIA        MD0040PA00X+008100Y+180200               S0      
317P12V_AUX         VIA        MD0040PA00X+008510Y+184450               S0      
317P12V_AUX         VIA        MD0040PA00X+008570Y+185230               S0      
317P12V_AUX         VIA        MD0040PA00X+008650Y+170011               S0      
317P12V_AUX         VIA        MD0040PA00X+008650Y+171361               S0      
317P12V_AUX         VIA        MD0040PA00X+008650Y+172600               S0      
317P12V_AUX         VIA        MD0040PA00X+008650Y+179311               S0      
317P12V_AUX         VIA        MD0040PA00X+008700Y+177411               S0      
317P12V_AUX         VIA        MD0040PA00X+008850Y+178500               S0      
317P12V_AUX         VIA        MD0040PA00X+009700Y+185050               S0      
317P12V_AUX         VIA        MD0040PA00X+009750Y+177550               S0      
317P12V_AUX         VIA        MD0040PA00X+009750Y+179600               S0      
317P12V_AUX         VIA        MD0040PA00X+009800Y+178600               S0      
317P12V_AUX         VIA        MD0040PA00X+009850Y+169650               S0      
317P12V_AUX         VIA        MD0040PA00X+009850Y+171700               S0      
317P12V_AUX         VIA        MD0040PA00X+009900Y+170700               S0      
327D_LATCH_PRE#                 D0040PA01X+016350Y+071010               S0      
317D_LATCH_PRE#                 D0040PA01X+005660Y+019160               S0      
317D_LATCH_PRE#                 D0040PA01X+016330Y+070210               S0      
317D_LATCH_PRE#                 D0040PA01X+015850Y+070270               S0      
317D_LATCH_PRE#                 D0040PA01X+005690Y+018730               S0      
317D_LATCH_PRE#     VIA        MD0040PA01X+015850Y+069500               S0      
317D_LATCH_PRE#     VIA        MD0040PA00X+016150Y+069170               S0      
317D_LATCH_PRE#     VIA        MD0040PA00X+005340Y+019130               S0      
317P3V3_AUX                     D0040PA01X+015450Y+069930               S0      
327P3V3_AUX                     D0040PA01X+016606Y+073230               S0      
327P3V3_AUX                     D0040PA01X+015838Y+073230               S0      
327P3V3_AUX                     D0040PA01X+015583Y+073230               S0      
317P3V3_AUX                     D0040PA01X+015050Y+069920               S0      
327P3V3_AUX                     D0040PA01X+013928Y+072255               S0      
317P3V3_AUX                     D0040PA01X+016770Y+069620               S0      
317P3V3_AUX                     D0040PA01X+014950Y+070830               S0      
327P3V3_AUX                     D0040PA01X+014700Y+072100               S0      
317P3V3_AUX                     D0040PA01X+015850Y+069930               S0      
317P3V3_AUX         VIA        MD0040PA01X+014200Y+070100               S0      
317P3V3_AUX         VIA        MD0040PA01X+017300Y+069100               S0      
317NNAME00000                   D0040PA01X+015730Y+145800               S0      
327NNAME00000                   D0040PA01X+014257Y+142977               S0      
317NNAME00000                   D0040PA01X+015138Y+144475               S0      
317NNAME00000                   D0040PA01X+016030Y+146250               S0      
317NNAME00000       VIA        MD0040PA04X+015600Y+144750               S0      
317NNAME00000       VIA        MD0040PA00X+015150Y+143850               S0      
317NNAME00000       VIA        MD0040PA00X+015750Y+145480               S0      
317TEMP_ALM#_IN_D               D0040PA01X+014430Y+069550               S0      
317TEMP_ALM#_IN_D               D0040PA01X+015450Y+070270               S0      
327TEMP_ALM#_IN_D               D0040PA01X+016094Y+071010               S0      
327TEMP_ALM#_IN_D               D0040PA01X+014550Y+068975               S0      
317TEMP_ALM#_IN_D   VIA        MD0040PA04X+015200Y+069569               S0      
317TEMP_ALM#_IN_D   VIA        MD0040PA00X+015070Y+069170               S0      
317TEMP_ALM#_IN_D   VIA        MD0040PA00X+015319Y+070589               S0      
327P12V                         D0040PA01X+003465Y+178100               S0      
317P12V                         D0040PA01X+006800Y+005310               S0      
327P12V                         D0040PA01X+007200Y+049145               S0      
327P12V                         D0040PA01X+003900Y+102250               S0      
327P12V                         D0040PA01X+016250Y+157550               S0      
327P12V                         D0040PA01X+016750Y+157550               S0      
327P12V                         D0040PA01X+017250Y+157550               S0      
317P12V                         D0040PA01X+014430Y+111690               S0      
327P12V                         D0040PA01X+015800Y+049095               S0      
317P12V                         D0040PA01X+007580Y+102090               S0      
327P12V                         D0040PA01X+004990Y+088380               S0      
327P12V                         D0040PA01X+004390Y+066700               S0      
327P12V                         D0040PA01X+007890Y+152350               S0      
317P12V                         D0040PA01X+007220Y+117510               S0      
327P12V                         D0040PA01X+002530Y+032850               S0      
317P12V                         D0040PA01X+003340Y+057080               S0      
327P12V                         D0040PA01X+009015Y+077670               S0      
317P12V                         D0040PA01X+014900Y+111695               S0      
327P12V                         D0040PA01X+014580Y+112650               S0      
317P12V                         D0040PA01X+004750Y+024450               S0      
317P12V                         D0040PA01X+009970Y+105840               S0      
317P12V                         D0040PA01X+015620Y+058700               S0      
327P12V                         D0040PA01X+004160Y+175425               S0      
327P12V                         D0040PA01X+006140Y+155150               S0      
317P12V                         D0040PA01X+003900Y+057790               S0      
317P12V                         D0040PA01X+005820Y+066230               S0      
327P12V                         D0040PA01X+009850Y+188320               S0      
327P12V                         D0040PA01X+012430Y+188350               S0      
327P12V                         D0040PA01X+001580Y+169920               S0      
317P12V                         D0040PA01X+008970Y+073340               S0      
317P12V                         D0040PA01X+015800Y+057860               S0      
327P12V                         D0040PA01X+009000Y+049145               S0      
317P12V                         D0040PA01X+007070Y+006350               S0      
327P12V                         D0040PA01X+006040Y+157560               S0      
327P12V                         D0040PA01X+006540Y+157560               S0      
327P12V                         D0040PA01X+007040Y+157560               S0      
317P12V                         D0040PA01X+006740Y+006760               S0      
327P12V                         D0040PA01X+009465Y+074040               S0      
317P12V                         D0040PA01X+009120Y+070790               S0      
317P12V                         D0040PA01X+014850Y+147070               S0      
317P12V                         D0040PA01X+005820Y+065760               S0      
327P12V                         D0040PA01X+008850Y+112295               S0      
317P12V                         D0040PA01X+014390Y+146240               S0      
327P12V                         D0040PA01X+001620Y+165710               S0      
327P12V                         D0040PA01X+010510Y+113555               S0      
317P12V                         D0040PA01X+007570Y+102540               S0      
327P12V                         D0040PA01X+009050Y+105010               S0      
327P12V                         D0040PA01X+007595Y+106970               S0      
317P12V                         D0040PA01X+007210Y+100430               S0      
327P12V                         D0040PA01X+009840Y+079840               S0      
317P12V                         D0040PA01X+011020Y+076410               S0      
317P12V                         D0040PA01X+017060Y+052910               S0      
317P12V                         D0040PA01X+004830Y+175230               S0      
327P12V                         D0040PA01X+007345Y+101180               S0      
327P12V                         D0040PA01X+016020Y+155160               S0      
317P12V                         D0040PA01X+008140Y+112270               S0      
327P12V                         D0040PA01X+005835Y+058400               S0      
327P12V                         D0040PA01X+012210Y+112530               S0      
317P12V                         D0040PA01X+014390Y+146640               S0      
327P12V                         D0040PA01X+008850Y+109060               S0      
317P12V                         D0040PA01X+010390Y+048220               S0      
327P12V                         D0040PA01X+007340Y+063350               S0      
327P12V                         D0040PA01X+009515Y+071540               S0      
327P12V                         D0040PA01X+008010Y+189195               S0      
317P12V                         D0040PA01X+014185Y+187870               S0      
317P12V                         D0040PA01X+003840Y+178820               S0      
317P12V                         D0040PA01X+009610Y+053050               S0      
317P12V                         D0040PA01X+005710Y+097930               S0      
327P12V                         D0040PA01X+007775Y+103210               S0      
327P12V                         D0040PA01X+009900Y+008620               S0      
317P12V                         D0040PA01X+003410Y+177440               S0      
317P12V                         D0040PA01X+014670Y+048230               S0      
327P12V                         D0040PA01X+003890Y+024690               S0      
327P12V                         D0040PA01X+017600Y+049095               S0      
327P12V                         D0040PA01X+009940Y+075790               S0      
327P12V                         D0040PA01X+015784Y+150770               S0      
327P12V                         D0040PA01X+009350Y+157550               S0      
327P12V                         D0040PA01X+009850Y+157550               S0      
327P12V                         D0040PA01X+010350Y+157550               S0      
327P12V                         D0040PA01X+005600Y+062345               S0      
327P12V                         D0040PA01X+016010Y+153150               S0      
317P12V                         D0040PA01X+005220Y+024450               S0      
327P12V                         D0040PA01X+005835Y+059300               S0      
327P12V                         D0040PA01X+010915Y+006850               S0      
317P12V                         D0040PA01X+014180Y+188370               S0      
327P12V                         D0040PA01X+008555Y+010300               S0      
317P12V                         D0040PA01X+009970Y+105370               S0      
327P12V                         D0040PA01X+007020Y+112505               S0      
327P12V                         D0040PA01X+012850Y+157550               S0      
327P12V                         D0040PA01X+013350Y+157550               S0      
327P12V                         D0040PA01X+013850Y+157550               S0      
327P12V                         D0040PA01X+011310Y+008850               S0      
317P12V                         D0040PA01X+011020Y+076910               S0      
317P12V                         D0040PA01X+006100Y+057720               S0      
327P12V                         D0040PA01X+009125Y+005450               S0      
317P12V                         D0040PA01X+006870Y+073000               S0      
317P12V                         D0040PA01X+006350Y+112040               S0      
317P12V             VIA        MD0040PA01X+010550Y+073200               S0      
317P12V             VIA        MD0040PA01X+010900Y+080950               S0      
317P12V             VIA        MD0040PA01X+011500Y+048610               S0      
317P12V             VIA        MD0040PA01X+011750Y+151950               S0      
317P12V             VIA        MD0040PA01X+013700Y+187750               S0      
317P12V             VIA        MD0040PA01X+013986Y+188946               S0      
317P12V             VIA        MD0040PA01X+014900Y+052250               S0      
317P12V             VIA        MD0040PA01X+019750Y+048150               S0      
317P12V             VIA        MD0040PA01X+004334Y+065015               S0      
317P12V             VIA        MD0040PA01X+004967Y+064293               S0      
317P12V             VIA        MD0040PA01X+006600Y+051050               S0      
317P12V             VIA        MD0040PA01X+008550Y+100950               S0      
317P12V             VIA        MD0040PA01X+009150Y+103050               S0      
317P12V             VIA        MD0040PA01X+009550Y+072800               S0      
317P12V             VIA        MD0040PA01X+009800Y+156470               S0      
317P12V             VIA        MD0040PA00X+010450Y+010100               S0      
317P12V             VIA        MD0040PA00X+001050Y+164880               S0      
317P12V             VIA        MD0040PA00X+010900Y+007650               S0      
317P12V             VIA        MD0040PA00X+010950Y+006200               S0      
317P12V             VIA        MD0040PA00X+011200Y+010100               S0      
317P12V             VIA        MD0040PA00X+011500Y+007650               S0      
317P12V             VIA        MD0040PA00X+011550Y+005950               S0      
317P12V             VIA        MD0040PA00X+014400Y+050950               S0      
317P12V             VIA        MD0040PA00X+015460Y+058150               S0      
317P12V             VIA        MD0040PA00X+015925Y+059025               S0      
317P12V             VIA        MD0040PA00X+016610Y+052790               S0      
317P12V             VIA        MD0040PA00X+002160Y+033380               S0      
317P12V             VIA        MD0040PA00X+003345Y+057430               S0      
317P12V             VIA        MD0040PA00X+004250Y+025410               S0      
317P12V             VIA        MD0040PA00X+004600Y+051600               S0      
317P12V             VIA        MD0040PA00X+004650Y+051100               S0      
317P12V             VIA        MD0040PA00X+004850Y+024860               S0      
317P12V             VIA        MD0040PA00X+005210Y+051310               S0      
317P12V             VIA        MD0040PA00X+005570Y+088000               S0      
317P12V             VIA        MD0040PA00X+006340Y+058140               S0      
317P12V             VIA        MD0040PA00X+006400Y+006755               S0      
317P12V             VIA        MD0040PA00X+006450Y+005300               S0      
317P12V             VIA        MD0040PA00X+006900Y+072680               S0      
317P12V             VIA        MD0040PA00X+007045Y+006003               S0      
317P12V             VIA        MD0040PA00X+007110Y+117100               S0      
317P12V             VIA        MD0040PA00X+008209Y+111250               S0      
317P12V             VIA        MD0040PA00X+008950Y+004950               S0      
317P12V             VIA        MD0040PA00X+009100Y+009700               S0      
317P12V             VIA        MD0040PA00X+009125Y+070470               S0      
317P12V             VIA        MD0040PA00X+009130Y+052820               S0      
317P12V             VIA        MD0040PA00X+009150Y+008850               S0      
317P12V             VIA        MD0040PA00X+009150Y+009250               S0      
317P12V             VIA        MD0040PA00X+009300Y+010700               S0      
317P12V             VIA        MD0040PA00X+009350Y+010150               S0      
317P12V             VIA        MD0040PA00X+009390Y+011180               S0      
317P12V             VIA        MD0040PA00X+009700Y+005150               S0      
317P12V             VIA        MD0040PA00X+009850Y+007300               S0      
317P12V             VIA        MD0040PA00X+009950Y+006100               S0      
317P12V             VIA        MD0040PA00X+010000Y+048800               S0      
317P12V             VIA        MD0040PA00X+010000Y+049400               S0      
317P12V             VIA        MD0040PA00X+010000Y+050000               S0      
317P12V             VIA        MD0040PA00X+010000Y+050600               S0      
317P12V             VIA        MD0040PA00X+010000Y+051200               S0      
317P12V             VIA        MD0040PA00X+010000Y+051910               S0      
317P12V             VIA        MD0040PA00X+010150Y+112750               S0      
317P12V             VIA        MD0040PA00X+010200Y+154400               S0      
317P12V             VIA        MD0040PA00X+010200Y+155000               S0      
317P12V             VIA        MD0040PA00X+010200Y+155600               S0      
317P12V             VIA        MD0040PA00X+010200Y+156200               S0      
317P12V             VIA        MD0040PA00X+010200Y+156800               S0      
317P12V             VIA        MD0040PA00X+010600Y+112750               S0      
317P12V             VIA        MD0040PA00X+010688Y+079420               S0      
317P12V             VIA        MD0040PA00X+010700Y+079820               S0      
317P12V             VIA        MD0040PA00X+010700Y+080240               S0      
317P12V             VIA        MD0040PA00X+011080Y+048260               S0      
317P12V             VIA        MD0040PA00X+011080Y+048860               S0      
317P12V             VIA        MD0040PA00X+011080Y+049460               S0      
317P12V             VIA        MD0040PA00X+011080Y+050060               S0      
317P12V             VIA        MD0040PA00X+011080Y+050660               S0      
317P12V             VIA        MD0040PA00X+011080Y+051260               S0      
317P12V             VIA        MD0040PA00X+011150Y+153750               S0      
317P12V             VIA        MD0040PA00X+011400Y+154600               S0      
317P12V             VIA        MD0040PA00X+011400Y+155200               S0      
317P12V             VIA        MD0040PA00X+011400Y+155800               S0      
317P12V             VIA        MD0040PA00X+011400Y+156400               S0      
317P12V             VIA        MD0040PA00X+011590Y+156970               S0      
317P12V             VIA        MD0040PA00X+011600Y+157600               S0      
317P12V             VIA        MD0040PA00X+011695Y+189200               S0      
317P12V             VIA        MD0040PA00X+011900Y+152950               S0      
317P12V             VIA        MD0040PA00X+012000Y+048550               S0      
317P12V             VIA        MD0040PA00X+012000Y+049350               S0      
317P12V             VIA        MD0040PA00X+012000Y+050150               S0      
317P12V             VIA        MD0040PA00X+012000Y+050950               S0      
317P12V             VIA        MD0040PA00X+012000Y+051750               S0      
317P12V             VIA        MD0040PA00X+012000Y+052350               S0      
317P12V             VIA        MD0040PA00X+012180Y+156993               S0      
317P12V             VIA        MD0040PA00X+012200Y+153800               S0      
317P12V             VIA        MD0040PA00X+012200Y+154600               S0      
317P12V             VIA        MD0040PA00X+012200Y+155200               S0      
317P12V             VIA        MD0040PA00X+012200Y+155800               S0      
317P12V             VIA        MD0040PA00X+012200Y+156400               S0      
317P12V             VIA        MD0040PA00X+012200Y+157600               S0      
317P12V             VIA        MD0040PA00X+012450Y+152400               S0      
317P12V             VIA        MD0040PA00X+012450Y+189240               S0      
317P12V             VIA        MD0040PA00X+012800Y+156800               S0      
317P12V             VIA        MD0040PA00X+012900Y+153500               S0      
317P12V             VIA        MD0040PA00X+012900Y+154250               S0      
317P12V             VIA        MD0040PA00X+012900Y+154900               S0      
317P12V             VIA        MD0040PA00X+012900Y+155550               S0      
317P12V             VIA        MD0040PA00X+012900Y+156250               S0      
317P12V             VIA        MD0040PA00X+012900Y+048550               S0      
317P12V             VIA        MD0040PA00X+012900Y+049350               S0      
317P12V             VIA        MD0040PA00X+012900Y+050150               S0      
317P12V             VIA        MD0040PA00X+012900Y+050950               S0      
317P12V             VIA        MD0040PA00X+012900Y+051750               S0      
317P12V             VIA        MD0040PA00X+012900Y+052350               S0      
317P12V             VIA        MD0040PA00X+013200Y+189200               S0      
317P12V             VIA        MD0040PA00X+013600Y+152800               S0      
317P12V             VIA        MD0040PA00X+013600Y+153600               S0      
317P12V             VIA        MD0040PA00X+013600Y+154200               S0      
317P12V             VIA        MD0040PA00X+013600Y+154800               S0      
317P12V             VIA        MD0040PA00X+013600Y+155500               S0      
317P12V             VIA        MD0040PA00X+013600Y+156200               S0      
317P12V             VIA        MD0040PA00X+013600Y+156800               S0      
317P12V             VIA        MD0040PA00X+013650Y+048550               S0      
317P12V             VIA        MD0040PA00X+013700Y+049300               S0      
317P12V             VIA        MD0040PA00X+013700Y+050150               S0      
317P12V             VIA        MD0040PA00X+013700Y+051000               S0      
317P12V             VIA        MD0040PA00X+013750Y+051750               S0      
317P12V             VIA        MD0040PA00X+013750Y+052350               S0      
317P12V             VIA        MD0040PA00X+001390Y+170620               S0      
317P12V             VIA        MD0040PA00X+014400Y+048618               S0      
317P12V             VIA        MD0040PA00X+014400Y+049350               S0      
317P12V             VIA        MD0040PA00X+014400Y+050150               S0      
317P12V             VIA        MD0040PA00X+014400Y+051750               S0      
317P12V             VIA        MD0040PA00X+014800Y+152800               S0      
317P12V             VIA        MD0040PA00X+014800Y+154200               S0      
317P12V             VIA        MD0040PA00X+014800Y+155000               S0      
317P12V             VIA        MD0040PA00X+014800Y+155800               S0      
317P12V             VIA        MD0040PA00X+014800Y+156400               S0      
317P12V             VIA        MD0040PA00X+014830Y+146500               S0      
317P12V             VIA        MD0040PA00X+015000Y+157000               S0      
317P12V             VIA        MD0040PA00X+015000Y+157600               S0      
317P12V             VIA        MD0040PA00X+015400Y+156400               S0      
317P12V             VIA        MD0040PA00X+015500Y+112000               S0      
317P12V             VIA        MD0040PA00X+015500Y+112500               S0      
317P12V             VIA        MD0040PA00X+015500Y+113050               S0      
317P12V             VIA        MD0040PA00X+015600Y+157000               S0      
317P12V             VIA        MD0040PA00X+015600Y+157600               S0      
317P12V             VIA        MD0040PA00X+015680Y+050690               S0      
317P12V             VIA        MD0040PA00X+015680Y+051540               S0      
317P12V             VIA        MD0040PA00X+015710Y+050000               S0      
317P12V             VIA        MD0040PA00X+016130Y+156310               S0      
317P12V             VIA        MD0040PA00X+016140Y+154350               S0      
317P12V             VIA        MD0040PA00X+016690Y+156710               S0      
317P12V             VIA        MD0040PA00X+016850Y+152600               S0      
317P12V             VIA        MD0040PA00X+016850Y+153350               S0      
317P12V             VIA        MD0040PA00X+016920Y+048280               S0      
317P12V             VIA        MD0040PA00X+016950Y+156150               S0      
317P12V             VIA        MD0040PA00X+017000Y+154100               S0      
317P12V             VIA        MD0040PA00X+017000Y+154850               S0      
317P12V             VIA        MD0040PA00X+017000Y+155500               S0      
317P12V             VIA        MD0040PA00X+017350Y+050600               S0      
317P12V             VIA        MD0040PA00X+017360Y+049880               S0      
317P12V             VIA        MD0040PA00X+017370Y+051390               S0      
317P12V             VIA        MD0040PA00X+017400Y+151550               S0      
317P12V             VIA        MD0040PA00X+017400Y+152200               S0      
317P12V             VIA        MD0040PA00X+017450Y+150350               S0      
317P12V             VIA        MD0040PA00X+017450Y+150950               S0      
317P12V             VIA        MD0040PA00X+017490Y+052330               S0      
317P12V             VIA        MD0040PA00X+018650Y+049800               S0      
317P12V             VIA        MD0040PA00X+018650Y+050600               S0      
317P12V             VIA        MD0040PA00X+018650Y+051350               S0      
317P12V             VIA        MD0040PA00X+018650Y+051900               S0      
317P12V             VIA        MD0040PA00X+019020Y+052340               S0      
317P12V             VIA        MD0040PA00X+019200Y+049000               S0      
317P12V             VIA        MD0040PA00X+019200Y+049800               S0      
317P12V             VIA        MD0040PA00X+019200Y+050600               S0      
317P12V             VIA        MD0040PA00X+019200Y+051350               S0      
317P12V             VIA        MD0040PA00X+019360Y+051910               S0      
317P12V             VIA        MD0040PA00X+019950Y+048940               S0      
317P12V             VIA        MD0040PA00X+019980Y+050600               S0      
317P12V             VIA        MD0040PA00X+020010Y+051360               S0      
317P12V             VIA        MD0040PA00X+020030Y+049810               S0      
317P12V             VIA        MD0040PA00X+020109Y+052350               S0      
317P12V             VIA        MD0040PA00X+020120Y+051920               S0      
317P12V             VIA        MD0040PA00X+003160Y+102430               S0      
317P12V             VIA        MD0040PA00X+003880Y+177500               S0      
317P12V             VIA        MD0040PA00X+003910Y+067492               S0      
317P12V             VIA        MD0040PA00X+004000Y+065900               S0      
317P12V             VIA        MD0040PA00X+004160Y+174690               S0      
317P12V             VIA        MD0040PA00X+004200Y+178440               S0      
317P12V             VIA        MD0040PA00X+004250Y+049300               S0      
317P12V             VIA        MD0040PA00X+004328Y+067499               S0      
317P12V             VIA        MD0040PA00X+004600Y+049050               S0      
317P12V             VIA        MD0040PA00X+004840Y+174690               S0      
317P12V             VIA        MD0040PA00X+005010Y+049300               S0      
317P12V             VIA        MD0040PA00X+005170Y+052250               S0      
317P12V             VIA        MD0040PA00X+005350Y+151900               S0      
317P12V             VIA        MD0040PA00X+005430Y+154120               S0      
317P12V             VIA        MD0040PA00X+005450Y+157400               S0      
317P12V             VIA        MD0040PA00X+005700Y+156850               S0      
317P12V             VIA        MD0040PA00X+005750Y+156200               S0      
317P12V             VIA        MD0040PA00X+005850Y+151900               S0      
317P12V             VIA        MD0040PA00X+005950Y+154100               S0      
317P12V             VIA        MD0040PA00X+006400Y+098050               S0      
317P12V             VIA        MD0040PA00X+007180Y+050690               S0      
317P12V             VIA        MD0040PA00X+007190Y+050100               S0      
317P12V             VIA        MD0040PA00X+007200Y+151400               S0      
317P12V             VIA        MD0040PA00X+007200Y+051480               S0      
317P12V             VIA        MD0040PA00X+007210Y+052180               S0      
317P12V             VIA        MD0040PA00X+007390Y+153590               S0      
317P12V             VIA        MD0040PA00X+007800Y+051480               S0      
317P12V             VIA        MD0040PA00X+007820Y+050100               S0      
317P12V             VIA        MD0040PA00X+007850Y+050670               S0      
317P12V             VIA        MD0040PA00X+007940Y+052180               S0      
317P12V             VIA        MD0040PA00X+008000Y+153160               S0      
317P12V             VIA        MD0040PA00X+008200Y+048360               S0      
317P12V             VIA        MD0040PA00X+008350Y+106700               S0      
317P12V             VIA        MD0040PA00X+008350Y+107200               S0      
317P12V             VIA        MD0040PA00X+008350Y+107650               S0      
317P12V             VIA        MD0040PA00X+008450Y+051440               S0      
317P12V             VIA        MD0040PA00X+008500Y+050640               S0      
317P12V             VIA        MD0040PA00X+008520Y+151500               S0      
317P12V             VIA        MD0040PA00X+008700Y+106400               S0      
317P12V             VIA        MD0040PA00X+008790Y+152340               S0      
317P12V             VIA        MD0040PA00X+009140Y+106410               S0      
317P12V             VIA        MD0040PA00X+009300Y+151870               S0      
317P12V             VIA        MD0040PA00X+009400Y+151400               S0      
317P12V             VIA        MD0040PA00X+009400Y+155000               S0      
317P12V             VIA        MD0040PA00X+009400Y+155600               S0      
317P12V             VIA        MD0040PA00X+009400Y+156200               S0      
317P12V             VIA        MD0040PA00X+009400Y+156800               S0      
317P12V             VIA        MD0040PA00X+009550Y+106400               S0      
317P12V             VIA        MD0040PA00X+009700Y+112750               S0      
317P12V             VIA        MD0040PA00X+009725Y+102350               S0      
317P12V             VIA        MD0040PA00X+009750Y+113250               S0      
317P12V             VIA        MD0040PA00X+009980Y+048200               S0      
327OTP_RETRY_G                  D0040PA01X+011700Y+138750               S0      
327OTP_RETRY_G                  D0040PA01X+013570Y+139230               S0      
317OTP_RETRY_G                  D0040PA01X+013500Y+140840               S0      
317OTP_RETRY_G                  D0040PA01X+012113Y+140195               S0      
317OTP_RETRY_G                  D0040PA01X+013470Y+140400               S0      
327OTP_RETRY_G                  D0040PA01X+014300Y+138750               S0      
317OTP_RETRY_G      VIA        MD0040PA01X+012286Y+138550               S0      
317FAN_TACH12                   D0040PA00X+001591Y+006811               S0      
317FAN_TACH12                   D0040PA01X+007570Y+007150               S0      
317FAN_TACH12                   D0040PA01X+006740Y+007100               S0      
317FAN_TACH12                   D0040PA01X+007140Y+007175               S0      
327FAN_TACH12                   D0040PA01X+009585Y+006850               S0      
317FAN_TACH10                   D0040PA00X+001591Y+050134               S0      
317FAN_TACH10                   D0040PA01X+003900Y+058130               S0      
317FAN_TACH10                   D0040PA01X+003500Y+058130               S0      
327FAN_TACH10                   D0040PA01X+004505Y+059300               S0      
317FAN_TACH10                   D0040PA01X+004510Y+058290               S0      
317FAN_TACH10       VIA        MD0040PA01X+002710Y+057810               S0      
317FAN_TACH10       VIA        MD0040PA00X+002515Y+057080               S0      
317FAN_TACH11                   D0040PA01X+006800Y+005650               S0      
317FAN_TACH11                   D0040PA00X+001591Y+004811               S0      
317FAN_TACH11                   D0040PA01X+007180Y+005655               S0      
317FAN_TACH11                   D0040PA01X+007825Y+006140               S0      
327FAN_TACH11                   D0040PA01X+007795Y+005450               S0      
317NCT7904_3VSB                 D0040PA01X+017642Y+061354               S0      
327NCT7904_3VSB                 D0040PA01X+017010Y+060760               S0      
317NCT7904_3VSB                 D0040PA01X+009727Y+059407               S0      
317NCT7904_3VSB                 D0040PA01X+016460Y+060850               S0      
327NCT7904_3VSB                 D0040PA01X+013624Y+062441               S0      
327NCT7904_3VSB                 D0040PA01X+010284Y+061850               S0      
317NCT7904_3VSB     VIA        MD0040PA01X+017630Y+060863               S0      
317FAN_TACH9                    D0040PA00X+001591Y+048134               S0      
317FAN_TACH9                    D0040PA01X+006790Y+059100               S0      
327FAN_TACH9                    D0040PA01X+007165Y+058400               S0      
317FAN_TACH9                    D0040PA01X+006450Y+057300               S0      
317FAN_TACH9                    D0040PA01X+006440Y+057720               S0      
317FAN_TACH9        VIA        MD0040PA04X+001804Y+057208               S0      
317FAN_TACH9        VIA        MD0040PA00X+002345Y+057749               S0      
317FAN_TACH6                    D0040PA01X+005810Y+103080               S0      
317FAN_TACH6                    D0040PA01X+006760Y+102500               S0      
317FAN_TACH6                    D0040PA01X+007230Y+102540               S0      
327FAN_TACH6                    D0040PA01X+006445Y+103210               S0      
317FAN_TACH6                    D0040PA00X+001591Y+120732               S0      
317FAN_TACH7                    D0040PA01X+007570Y+071910               S0      
317FAN_TACH7                    D0040PA01X+008780Y+070790               S0      
317FAN_TACH7                    D0040PA00X+001591Y+074118               S0      
317FAN_TACH7                    D0040PA01X+008200Y+070820               S0      
327FAN_TACH7                    D0040PA01X+008185Y+071540               S0      
317FAN_TACH8                    D0040PA01X+008150Y+073320               S0      
317FAN_TACH8                    D0040PA01X+008630Y+073340               S0      
327FAN_TACH8                    D0040PA01X+008135Y+074040               S0      
317FAN_TACH8                    D0040PA01X+007520Y+074150               S0      
317FAN_TACH8                    D0040PA00X+001591Y+076118               S0      
317FAN_TACH5                    D0040PA01X+005380Y+101310               S0      
317FAN_TACH5                    D0040PA01X+006870Y+100430               S0      
327FAN_TACH5                    D0040PA01X+006015Y+101180               S0      
317FAN_TACH5                    D0040PA00X+001591Y+118732               S0      
317FAN_TACH5                    D0040PA01X+006420Y+100410               S0      
317FAN_TACH3                    D0040PA00X+001591Y+144717               S0      
317FAN_TACH3                    D0040PA01X+007120Y+114450               S0      
317FAN_TACH3                    D0040PA01X+006320Y+112835               S0      
327FAN_TACH3                    D0040PA01X+007020Y+113835               S0      
317FAN_TACH3                    D0040PA01X+006350Y+112380               S0      
317FAN_TACH3        VIA        MD0040PA04X+003044Y+136756               S0      
317FAN_TACH3        VIA        MD0040PA00X+007050Y+116150               S0      
317FAN_TACH4                    D0040PA01X+008140Y+113215               S0      
317FAN_TACH4                    D0040PA00X+001591Y+146717               S0      
327FAN_TACH4                    D0040PA01X+008850Y+113625               S0      
317FAN_TACH4                    D0040PA01X+008700Y+114300               S0      
317FAN_TACH4                    D0040PA01X+008140Y+112610               S0      
317FAN_TACH4        VIA        MD0040PA00X+007316Y+115878               S0      
327FAN_TACH1                    D0040PA01X+002135Y+178100               S0      
317FAN_TACH1                    D0040PA01X+003030Y+178780               S0      
317FAN_TACH1                    D0040PA00X+001591Y+188039               S0      
317FAN_TACH1                    D0040PA01X+003070Y+177440               S0      
317FAN_TACH1                    D0040PA01X+003360Y+176990               S0      
317FAN_TACH1        VIA        MD0040PA01X+002006Y+177419               S0      
317FAN_TACH2                    D0040PA01X+004870Y+176470               S0      
327FAN_TACH2                    D0040PA01X+004160Y+176755               S0      
317FAN_TACH2                    D0040PA01X+004820Y+176030               S0      
317FAN_TACH2                    D0040PA01X+004830Y+175570               S0      
317FAN_TACH2                    D0040PA00X+001591Y+190039               S0      
317FAN_TACH2        VIA        MD0040PA01X+005700Y+180550               S0      
317NCT7904_VREF                 D0040PA01X+010350Y+059750               S0      
327NCT7904_VREF                 D0040PA01X+010871Y+061263               S0      
317NCT7904_VREF                 D0040PA01X+010500Y+060320               S0      
327NNAME00001                   D0040PA01X+015860Y+143800               S0      
317NNAME00001                   D0040PA01X+013320Y+142830               S0      
317NNAME00001                   D0040PA01X+006060Y+019500               S0      
317NNAME00001                   D0040PA01X+013330Y+143200               S0      
327NNAME00001                   D0040PA01X+013869Y+142227               S0      
317NNAME00001                   D0040PA01X+006030Y+019930               S0      
317NNAME00001                   D0040PA01X+014750Y+143725               S0      
317NNAME00001       VIA        MD0040PA04X+019201Y+048259               S0      
317NNAME00001       VIA        MD0040PA00X+014250Y+142050               S0      
317NNAME00001       VIA        MD0040PA00X+007050Y+019020               S0      
317NNAME00002                   D0040PA01X+005430Y+025990               S0      
317NNAME00002                   D0040PA00X+008071Y+022441               S0      
317NNAME00002                   D0040PA01X+005620Y+025280               S0      
317NNAME00002                   D0040PA00X+014961Y+022441               S0      
317NNAME00002                   D0040PA01X+006260Y+024920               S0      
317NNAME00003                   D0040PA00X+008071Y+024441               S0      
317NNAME00003                   D0040PA01X+005830Y+025990               S0      
317NNAME00003                   D0040PA01X+006270Y+025980               S0      
317NNAME00003                   D0040PA00X+014961Y+024441               S0      
317NNAME00003                   D0040PA01X+006300Y+026430               S0      
317ADM1276_ISET                 D0040PA01X+009470Y+144650               S0      
317ADM1276_ISET                 D0040PA01X+009470Y+143900               S0      
317ADM1276_ISET                 D0040PA01X+009480Y+144280               S0      
327ADM1276_ISET                 D0040PA01X+010740Y+145200               S0      
317ADM1276_ISET     VIA        MD0040PA01X+009970Y+145070               S0      
327NCT7904_D1+                  D0040PA01X+011202Y+056699               S0      
327NCT7904_D1+                  D0040PA01X+010452Y+057087               S0      
327NCT7904_D1+                  D0040PA01X+011067Y+061263               S0      
317NCT7904_D1+                  D0040PA01X+010760Y+059370               S0      
317NCT7904_D1+      VIA        MD0040PA01X+010634Y+058050               S0      
327NCT7904_D1-                  D0040PA01X+011202Y+057474               S0      
327NCT7904_D1-                  D0040PA01X+011265Y+061263               S0      
317NCT7904_D1-                  D0040PA01X+011120Y+059370               S0      
317NCT7904_D1-      VIA        MD0040PA01X+011202Y+058490               S0      
317NCT7904_D2+                  D0040PA01X+011290Y+060350               S0      
327NCT7904_D2+                  D0040PA01X+011202Y+125597               S0      
327NCT7904_D2+                  D0040PA01X+010452Y+125984               S0      
327NCT7904_D2+                  D0040PA01X+011462Y+061263               S0      
317NCT7904_D2+      VIA        MD0040PA04X+012400Y+124760               S0      
317NCT7904_D2+      VIA        MD0040PA00X+011366Y+059936               S0      
317NCT7904_D2+      VIA        MD0040PA00X+011900Y+125597               S0      
317NCT7904_D2-                  D0040PA01X+011650Y+060350               S0      
327NCT7904_D2-                  D0040PA01X+011202Y+126372               S0      
327NCT7904_D2-                  D0040PA01X+011658Y+061263               S0      
317NCT7904_D2-      VIA        MD0040PA04X+012269Y+125781               S0      
317NCT7904_D2-      VIA        MD0040PA00X+011600Y+059690               S0      
317NCT7904_D2-      VIA        MD0040PA00X+011950Y+126100               S0      
327P12V_FAN1                    D0040PA01X+009850Y+191000               S0      
327P12V_FAN1                    D0040PA01X+008010Y+189985               S0      
317P12V_FAN1                    D0040PA00X+001591Y+191039               S0      
317P12V_FAN1        VIA        MD0040PA01X+006600Y+191700               S0      
317P12V_FAN1        VIA        MD0040PA01X+008200Y+191500               S0      
317NNAME00004                   D0040PA01X+010260Y+088480               S0      
317NNAME00004                   D0040PA01X+003500Y+178820               S0      
317NNAME00004                   D0040PA00X+001591Y+189039               S0      
317NNAME00004       VIA        MD0040PA04X+005693Y+113003               S0      
317NNAME00004       VIA        MD0040PA00X+006460Y+088270               S0      
317NNAME00004       VIA        MD0040PA00X+003918Y+179231               S0      
317PWM_EXP_2B                   D0040PA01X+009470Y+067100               S0      
317PWM_EXP_2B                   D0040PA00X+014961Y+020441               S0      
327PWM_EXP_2B                   D0040PA01X+009321Y+067742               S0      
317PWM_EXP_2B       VIA        MD0040PA04X+010060Y+065660               S0      
317PWM_EXP_2B       VIA        MD0040PA00X+004992Y+015326               S0      
317PWM_EXP_2B       VIA        MD0040PA00X+007530Y+015530               S0      
317PWM_EXP_2B       VIA        MD0040PA00X+010060Y+067060               S0      
317PWM_EXP_2A                   D0040PA01X+012596Y+069217               S0      
317PWM_EXP_2A                   D0040PA00X+015961Y+023441               S0      
327PWM_EXP_2A                   D0040PA01X+011331Y+069242               S0      
317PWM_EXP_2A       VIA        MD0040PA00X+012070Y+069085               S0      
317SELF_2B_HB                   D0040PA00X+015961Y+021441               S0      
317SELF_2B_HB                   D0040PA01X+006030Y+016730               S0      
317NNAME00005                   D0040PA01X+015800Y+057520               S0      
317NNAME00005                   D0040PA00X+016961Y+024441               S0      
317NNAME00005       VIA        MD0040PA04X+018400Y+053650               S0      
317NNAME00005       VIA        MD0040PA00X+016000Y+056250               S0      
317NNAME00006                   D0040PA01X+015350Y+056660               S0      
317NNAME00006                   D0040PA01X+016570Y+055330               S0      
327NNAME00006                   D0040PA01X+015314Y+055925               S0      
327NNAME00006                   D0040PA01X+017210Y+054910               S0      
317NNAME00006                   D0040PA00X+016961Y+023441               S0      
317NNAME00006       VIA        MD0040PA00X+018259Y+054229               S0      
317SELF_2A_HB                   D0040PA00X+016961Y+022441               S0      
317SELF_2A_HB                   D0040PA01X+006030Y+018330               S0      
317SELF_2A_HB       VIA        MD0040PA00X+006440Y+018340               S0      
317SEB_PEER_2A_HB               D0040PA01X+006030Y+017130               S0      
317SEB_PEER_2A_HB               D0040PA01X+006030Y+017530               S0      
327SEB_PEER_2A_HB               D0040PA01X+005175Y+069056               S0      
317SEB_PEER_2A_HB               D0040PA00X+016961Y+021441               S0      
317SEB_PEER_2A_HB   VIA        MD0040PA00X+003243Y+017790               S0      
317SEB_PEER_2A_HB   VIA        MD0040PA00X+004450Y+069750               S0      
317SEB_PEER_2B_HB               D0040PA01X+006030Y+015930               S0      
327SEB_PEER_2B_HB               D0040PA01X+005175Y+068800               S0      
317SEB_PEER_2B_HB               D0040PA01X+005690Y+015530               S0      
317SEB_PEER_2B_HB               D0040PA00X+016961Y+020441               S0      
317SEB_PEER_2B_HB   VIA        MD0040PA00X+003930Y+017550               S0      
317SEB_PEER_2B_HB   VIA        MD0040PA00X+004339Y+069429               S0      
317NNAME00007                   D0040PA01X+004990Y+021340               S0      
317NNAME00007                   D0040PA00X+017961Y+024441               S0      
317NNAME00007       VIA        MD0040PA00X+012210Y+023010               S0      
317NNAME00007       VIA        MD0040PA00X+007530Y+021130               S0      
317LOWER_TRAY_ID                D0040PA01X+006120Y+021700               S0      
317LOWER_TRAY_ID                D0040PA01X+006120Y+022100               S0      
317LOWER_TRAY_ID                D0040PA00X+017961Y+023441               S0      
317LOWER_TRAY_ID    VIA        MD0040PA00X+011760Y+023490               S0      
317LOWER_TRAY_ID    VIA        MD0040PA00X+007060Y+021760               S0      
317NNAME00008                   D0040PA00X+011071Y+022441               S0      
317NNAME00008                   D0040PA00X+017961Y+022441               S0      
317NNAME00008                   D0040PA01X+006160Y+021130               S0      
317NNAME00008                   D0040PA01X+005740Y+021130               S0      
317NNAME00008       VIA        MD0040PA00X+007140Y+020815               S0      
317NNAME00009                   D0040PA01X+006060Y+019160               S0      
317NNAME00009                   D0040PA00X+017961Y+021441               S0      
317NNAME00009                   D0040PA01X+006030Y+018730               S0      
317NNAME00010                   D0040PA01X+004990Y+021740               S0      
317NNAME00010                   D0040PA00X+017961Y+020441               S0      
317NNAME00010       VIA        MD0040PA00X+007210Y+022170               S0      
317NNAME00010       VIA        MD0040PA00X+008568Y+023110               S0      
317P12V_FAN2                    D0040PA00X+001591Y+147717               S0      
327P12V_FAN2                    D0040PA01X+010510Y+114345               S0      
327P12V_FAN2                    D0040PA01X+012210Y+115210               S0      
317P12V_FAN2        VIA        MD0040PA01X+007100Y+123260               S0      
317NNAME00011                   D0040PA01X+006880Y+117510               S0      
317NNAME00011                   D0040PA00X+001591Y+145717               S0      
317NNAME00011                   D0040PA01X+011090Y+088480               S0      
317NNAME00011       VIA        MD0040PA04X+006090Y+089300               S0      
317NNAME00011       VIA        MD0040PA00X+006160Y+088520               S0      
317NNAME00011       VIA        MD0040PA00X+006880Y+117880               S0      
327P12V_FAN3                    D0040PA01X+006370Y+105010               S0      
327P12V_FAN3                    D0040PA01X+006805Y+106970               S0      
317P12V_FAN3                    D0040PA00X+001591Y+121732               S0      
317P12V_FAN3        VIA        MD0040PA01X+005210Y+113270               S0      
317NNAME00012                   D0040PA01X+007240Y+102090               S0      
317NNAME00012                   D0040PA01X+011930Y+088480               S0      
317NNAME00012                   D0040PA00X+001591Y+119732               S0      
317NNAME00012       VIA        MD0040PA04X+005850Y+091250               S0      
317NNAME00012       VIA        MD0040PA00X+005100Y+101800               S0      
317NNAME00012       VIA        MD0040PA00X+006720Y+088880               S0      
327P12V_FAN4                    D0040PA01X+008225Y+077670               S0      
317P12V_FAN4                    D0040PA00X+001591Y+077118               S0      
327P12V_FAN4                    D0040PA01X+007260Y+075790               S0      
317P12V_FAN4        VIA        MD0040PA01X+006500Y+076600               S0      
317P12V_FAN4        VIA        MD0040PA01X+006500Y+077500               S0      
317NNAME00013                   D0040PA01X+011960Y+082840               S0      
317NNAME00013                   D0040PA00X+001591Y+075118               S0      
317NNAME00013                   D0040PA01X+006530Y+073000               S0      
317NNAME00013       VIA        MD0040PA04X+010576Y+081426               S0      
317NNAME00013       VIA        MD0040PA00X+011490Y+082410               S0      
317NNAME00013       VIA        MD0040PA00X+008650Y+072350               S0      
317P12V_FAN5                    D0040PA00X+001591Y+051134               S0      
327P12V_FAN5                    D0040PA01X+007340Y+060670               S0      
327P12V_FAN5                    D0040PA01X+005600Y+061555               S0      
317P12V_FAN5        VIA        MD0040PA01X+001100Y+057800               S0      
317P12V_FAN5        VIA        MD0040PA01X+002730Y+059300               S0      
317P12V_FAN5        VIA        MD0040PA01X+003700Y+060500               S0      
317NNAME00014                   D0040PA00X+001591Y+049134               S0      
317NNAME00014                   D0040PA01X+003000Y+057080               S0      
317NNAME00014                   D0040PA01X+011120Y+082840               S0      
317NNAME00014       VIA        MD0040PA04X+003800Y+058950               S0      
317NNAME00014       VIA        MD0040PA00X+002700Y+057380               S0      
317NNAME00014       VIA        MD0040PA00X+005120Y+082700               S0      
317P12V_FAN6                    D0040PA00X+001591Y+007811               S0      
327P12V_FAN6                    D0040PA01X+007220Y+008620               S0      
327P12V_FAN6                    D0040PA01X+007765Y+010300               S0      
317NNAME00015                   D0040PA00X+001591Y+005811               S0      
317NNAME00015                   D0040PA01X+006730Y+006350               S0      
317NNAME00015                   D0040PA01X+010290Y+082840               S0      
317NNAME00015       VIA        MD0040PA04X+006960Y+066270               S0      
317NNAME00015       VIA        MD0040PA00X+006121Y+082835               S0      
317NNAME00015       VIA        MD0040PA00X+006350Y+006350               S0      
317PWM_EXP_1B                   D0040PA00X+008071Y+020441               S0      
317PWM_EXP_1B                   D0040PA01X+012586Y+068806               S0      
327PWM_EXP_1B                   D0040PA01X+011331Y+068742               S0      
317PWM_EXP_1B       VIA        MD0040PA00X+011958Y+068701               S0      
317PWM_EXP_1A                   D0040PA00X+009071Y+023441               S0      
317PWM_EXP_1A                   D0040PA01X+012586Y+068367               S0      
327PWM_EXP_1A                   D0040PA01X+011331Y+068242               S0      
317PWM_EXP_1A       VIA        MD0040PA00X+012150Y+068350               S0      
317SELF_1B_HB                   D0040PA01X+005690Y+015930               S0      
317SELF_1B_HB                   D0040PA00X+009071Y+021441               S0      
317SELF_1B_HB       VIA        MD0040PA00X+004970Y+020970               S0      
317SELF_1B_HB       VIA        MD0040PA00X+005270Y+016230               S0      
317NNAME00016                   D0040PA01X+015280Y+058700               S0      
317NNAME00016                   D0040PA00X+010071Y+024441               S0      
317NNAME00016       VIA        MD0040PA00X+014790Y+058810               S0      
317NNAME00017                   D0040PA01X+009630Y+056330               S0      
327NNAME00017                   D0040PA01X+008934Y+056105               S0      
327NNAME00017                   D0040PA01X+010760Y+055830               S0      
317NNAME00017                   D0040PA01X+009130Y+056980               S0      
317NNAME00017                   D0040PA00X+010071Y+023441               S0      
317NNAME00017       VIA        MD0040PA01X+009650Y+056760               S0      
317NNAME00017       VIA        MD0040PA00X+011530Y+055180               S0      
317NNAME00017       VIA        MD0040PA00X+012720Y+024600               S0      
317SELF_1A_HB                   D0040PA01X+005690Y+017530               S0      
317SELF_1A_HB                   D0040PA00X+010071Y+022441               S0      
317SELF_1A_HB       VIA        MD0040PA00X+004780Y+019920               S0      
317SELF_1A_HB       VIA        MD0040PA00X+005250Y+017520               S0      
317SELF_1A_HB       VIA        MD0040PA00X+005350Y+019970               S0      
317SEB_PEER_1A_HB               D0040PA00X+010071Y+021441               S0      
317SEB_PEER_1A_HB               D0040PA01X+005690Y+017930               S0      
327SEB_PEER_1A_HB               D0040PA01X+003625Y+069056               S0      
317SEB_PEER_1A_HB               D0040PA01X+005690Y+018330               S0      
317SEB_PEER_1A_HB   VIA        MD0040PA00X+004110Y+023100               S0      
317SEB_PEER_1A_HB   VIA        MD0040PA00X+004370Y+018120               S0      
317SEB_PEER_1A_HB   VIA        MD0040PA00X+004950Y+070350               S0      
317SEB_PEER_1B_HB               D0040PA00X+010071Y+020441               S0      
327SEB_PEER_1B_HB               D0040PA01X+003625Y+068800               S0      
317SEB_PEER_1B_HB               D0040PA01X+005690Y+016330               S0      
317SEB_PEER_1B_HB               D0040PA01X+005690Y+016730               S0      
317SEB_PEER_1B_HB   VIA        MD0040PA00X+003800Y+022850               S0      
317SEB_PEER_1B_HB   VIA        MD0040PA00X+004340Y+017432               S0      
317SEB_PEER_1B_HB   VIA        MD0040PA00X+004650Y+070550               S0      
317SEB_PEER_1B_HB   VIA        MD0040PA00X+006130Y+022940               S0      
317NNAME00018                   D0040PA00X+011071Y+024441               S0      
317NNAME00018                   D0040PA01X+004650Y+021740               S0      
317NNAME00018       VIA        MD0040PA00X+006940Y+022610               S0      
317NNAME00018       VIA        MD0040PA00X+007480Y+023180               S0      
317UPPER_TRAY_ID                D0040PA00X+011071Y+023441               S0      
317UPPER_TRAY_ID                D0040PA01X+005690Y+024000               S0      
317UPPER_TRAY_ID                D0040PA01X+006100Y+024000               S0      
317UPPER_TRAY_ID    VIA        MD0040PA00X+006990Y+023660               S0      
317UPPER_TRAY_ID    VIA        MD0040PA00X+007790Y+022903               S0      
317NNAME00019                   D0040PA01X+005660Y+019500               S0      
317NNAME00019                   D0040PA00X+011071Y+021441               S0      
317NNAME00019                   D0040PA01X+005690Y+019930               S0      
317NNAME00019       VIA        MD0040PA00X+006400Y+019970               S0      
317NNAME00020                   D0040PA00X+011071Y+020441               S0      
317NNAME00020                   D0040PA01X+004650Y+021340               S0      
327P3V3_AUX_BJT_B               D0040PA01X+013153Y+072255               S0      
327P3V3_AUX_BJT_B               D0040PA01X+013471Y+071050               S0      
317P3V3_AUX_BJT_B               D0040PA01X+012490Y+072260               S0      
317P3V3_AUX_BJT_B   VIA        MD0040PA01X+011750Y+072450               S0      
327NNAME00021                   D0040PA01X+015860Y+144640               S0      
317NNAME00021                   D0040PA01X+015233Y+143108               S0      
317NNAME00021                   D0040PA01X+015663Y+143108               S0      
327NNAME00021                   D0040PA01X+016937Y+144497               S0      
317NNAME00021       VIA        MD0040PA01X+016550Y+145060               S0      
327OTP_RETRY_C                  D0040PA01X+014110Y+140170               S0      
327OTP_RETRY_C                  D0040PA01X+015190Y+140895               S0      
317OTP_RETRY_C                  D0040PA01X+015550Y+141500               S0      
317OTP_RETRY_C      VIA        MD0040PA01X+015977Y+141437               S0      
327NNAME00022                   D0040PA01X+014110Y+141010               S0      
317NNAME00022                   D0040PA01X+013500Y+141180               S0      
317NNAME00022       VIA        MD0040PA01X+012900Y+141643               S0      
317TEMP_ALM#_JP_1               D0040PA01X+015550Y+142340               S0      
317TEMP_ALM#_JP_1               D0040PA00X+016500Y+137050               S0      
317TEMP_ALM#_JP_1               D0040PA01X+015663Y+142768               S0      
317TEMP_ALM#_JP_1               D0040PA01X+016083Y+142688               S0      
327TEMP_ALM#_JP_2               D0040PA01X+011380Y+140226               S0      
317TEMP_ALM#_JP_2               D0040PA00X+016500Y+138050               S0      
327OTP_RETRY_B                  D0040PA01X+014803Y+140145               S0      
317OTP_RETRY_B                  D0040PA00X+016500Y+139050               S0      
317OTP_RETRY_B                  D0040PA01X+015550Y+141920               S0      
317OTP_RETRY_B                  D0040PA01X+015140Y+139400               S0      
327NNAME00023                   D0040PA01X+002342Y+170737               S0      
317NNAME00023                   D0040PA01X+002360Y+169280               S0      
327NNAME00023                   D0040PA01X+002680Y+169920               S0      
317NNAME00023                   D0040PA00X+003130Y+173764               S0      
317NNAME00023       VIA        MD0040PA01X+003295Y+170945               S0      
317LED_DR_LED0_K                D0040PA01X+002590Y+172510               S0      
317LED_DR_LED0_K                D0040PA00X+003130Y+174764               S0      
327LED_DR_LED0                  D0040PA01X+014502Y+095950               S0      
317LED_DR_LED0                  D0040PA01X+014500Y+094920               S0      
317LED_DR_LED0                  D0040PA00X+003130Y+175764               S0      
317LED_DR_LED0                  D0040PA01X+001840Y+172070               S0      
317LED_DR_LED0      VIA        MD0040PA00X+014300Y+095303               S0      
317LED_DR_LED0      VIA        MD0040PA00X+001920Y+170700               S0      
327NNAME00024                   D0040PA01X+003150Y+164155               S0      
317NNAME00024                   D0040PA00X+003130Y+160994               S0      
317NNAME00024                   D0040PA01X+002200Y+164430               S0      
327NNAME00024                   D0040PA01X+002720Y+165710               S0      
317LED_DR_LED1_K                D0040PA00X+003130Y+161994               S0      
317LED_DR_LED1_K                D0040PA01X+002200Y+164020               S0      
317LED_DR_LED1                  D0040PA00X+003130Y+162994               S0      
327LED_DR_LED1                  D0040PA01X+014758Y+095950               S0      
317LED_DR_LED1                  D0040PA01X+003290Y+166420               S0      
317LED_DR_LED1                  D0040PA01X+014900Y+094920               S0      
317LED_DR_LED1      VIA        MD0040PA04X+012290Y+100740               S0      
317LED_DR_LED1      VIA        MD0040PA00X+014650Y+095303               S0      
317LED_DR_LED1      VIA        MD0040PA00X+001925Y+166310               S0      
327NNAME00025                   D0040PA01X+003900Y+103350               S0      
327NNAME00025                   D0040PA01X+002437Y+109308               S0      
317NNAME00025                   D0040PA00X+003130Y+104459               S0      
317NNAME00025                   D0040PA01X+002430Y+110600               S0      
317NNAME00025       VIA        MD0040PA01X+002450Y+110200               S0      
317LED_DR_LED2_K                D0040PA01X+003010Y+108360               S0      
317LED_DR_LED2_K                D0040PA00X+003130Y+105459               S0      
317LED_DR_LED2                  D0040PA00X+003130Y+106459               S0      
327LED_DR_LED2                  D0040PA01X+015014Y+095950               S0      
317LED_DR_LED2                  D0040PA01X+015300Y+094920               S0      
317LED_DR_LED2                  D0040PA01X+004140Y+109600               S0      
317LED_DR_LED2      VIA        MD0040PA04X+003750Y+099800               S0      
317LED_DR_LED2      VIA        MD0040PA00X+012720Y+101520               S0      
317LED_DR_LED2      VIA        MD0040PA00X+014977Y+095412               S0      
317LED_DR_LED2      VIA        MD0040PA00X+003750Y+109982               S0      
317LED_DR_LED2      VIA        MD0040PA00X+003770Y+099160               S0      
327NNAME00026                   D0040PA01X+004990Y+089480               S0      
317NNAME00026                   D0040PA01X+004340Y+089610               S0      
317NNAME00026                   D0040PA00X+003130Y+090392               S0      
327NNAME00026                   D0040PA01X+005482Y+090237               S0      
317NNAME00026       VIA        MD0040PA01X+006590Y+090000               S0      
317LED_DR_LED3_K                D0040PA00X+003130Y+091392               S0      
317LED_DR_LED3_K                D0040PA01X+004540Y+091640               S0      
317LED_DR_LED3                  D0040PA01X+015700Y+094920               S0      
327LED_DR_LED3                  D0040PA01X+015270Y+095950               S0      
317LED_DR_LED3                  D0040PA00X+003130Y+092392               S0      
317LED_DR_LED3                  D0040PA01X+006410Y+091280               S0      
317LED_DR_LED3      VIA        MD0040PA01X+007650Y+090050               S0      
317LED_DR_LED3      VIA        MD0040PA00X+014750Y+090050               S0      
317LED_DR_LED3      VIA        MD0040PA00X+015275Y+095247               S0      
327NNAME00027                   D0040PA01X+003630Y+032850               S0      
317NNAME00027                   D0040PA00X+003130Y+033856               S0      
317NNAME00027                   D0040PA01X+003250Y+032130               S0      
327NNAME00027                   D0040PA01X+002880Y+031285               S0      
317NNAME00027       VIA        MD0040PA01X+003620Y+031870               S0      
317LED_DR_LED4_K                D0040PA01X+003920Y+034720               S0      
317LED_DR_LED4_K                D0040PA00X+003130Y+034856               S0      
317LED_DR_LED4                  D0040PA01X+001928Y+031068               S0      
317LED_DR_LED4                  D0040PA01X+016350Y+099430               S0      
327LED_DR_LED4                  D0040PA01X+015526Y+098170               S0      
317LED_DR_LED4                  D0040PA00X+003130Y+035856               S0      
317LED_DR_LED4      VIA        MD0040PA04X+005781Y+085250               S0      
317LED_DR_LED4      VIA        MD0040PA00X+015500Y+097450               S0      
317LED_DR_LED4      VIA        MD0040PA00X+015780Y+089800               S0      
317LED_DR_LED4      VIA        MD0040PA00X+005600Y+088550               S0      
317NNAME00028                   D0040PA00X+003130Y+021087               S0      
327NNAME00028                   D0040PA01X+002360Y+025505               S0      
317NNAME00028                   D0040PA01X+003270Y+025350               S0      
327NNAME00028                   D0040PA01X+002790Y+024690               S0      
317LED_DR_LED5_K                D0040PA01X+003720Y+025350               S0      
317LED_DR_LED5_K                D0040PA00X+003130Y+022087               S0      
317LED_DR_LED5                  D0040PA00X+003130Y+023087               S0      
327LED_DR_LED5                  D0040PA01X+015270Y+098170               S0      
317LED_DR_LED5                  D0040PA01X+015950Y+099430               S0      
317LED_DR_LED5                  D0040PA01X+003608Y+026422               S0      
317LED_DR_LED5      VIA        MD0040PA04X+012860Y+066950               S0      
317LED_DR_LED5      VIA        MD0040PA00X+015050Y+097650               S0      
317LED_DR_LED5      VIA        MD0040PA00X+005400Y+027560               S0      
317OSC_TRI_S                    D0040PA01X+018037Y+064577               S0      
327OSC_TRI_S                    D0040PA01X+017137Y+064584               S0      
317OSC_TRI_S        VIA        MD0040PA01X+017410Y+065290               S0      
317NCT7904_CLK                  D0040PA01X+015134Y+063583               S0      
327NCT7904_CLK                  D0040PA01X+015980Y+063482               S0      
317NCT7904_CLK      VIA        MD0040PA01X+015134Y+064040               S0      
317ADM1276_VCC                  D0040PA01X+010680Y+147450               S0      
327ADM1276_VCC                  D0040PA01X+010677Y+148064               S0      
327ADM1276_VCC                  D0040PA01X+011444Y+146160               S0      
317ADM1276_VCC                  D0040PA01X+010750Y+148680               S0      
317ADM1276_VCC      VIA        MD0040PA01X+011183Y+146967               S0      
317ADM1276_UV                   D0040PA01X+008770Y+148400               S0      
317ADM1276_UV                   D0040PA01X+009130Y+145100               S0      
327ADM1276_UV                   D0040PA01X+008780Y+147750               S0      
317ADM1276_UV                   D0040PA01X+010050Y+142030               S0      
327ADM1276_UV                   D0040PA01X+011188Y+146160               S0      
317ADM1276_UV                   D0040PA01X+009350Y+147580               S0      
317ADM1276_UV       VIA        MD0040PA04X+008960Y+146400               S0      
317ADM1276_UV       VIA        MD0040PA00X+008690Y+145100               S0      
317ADM1276_UV       VIA        MD0040PA00X+009130Y+148860               S0      
317ADM1276_UV       VIA        MD0040PA00X+009960Y+141650               S0      
327ADM1276_SS                   D0040PA01X+010740Y+144944               S0      
317ADM1276_SS                   D0040PA01X+009480Y+143490               S0      
317ADM1276_SS       VIA        MD0040PA01X+010000Y+144300               S0      
317ADM1276_VCAP                 D0040PA01X+009470Y+145100               S0      
317ADM1276_VCAP                 D0040PA01X+009130Y+143900               S0      
327ADM1276_VCAP                 D0040PA01X+010740Y+145456               S0      
317ADM1276_VCAP                 D0040PA01X+009480Y+145550               S0      
317ADM1276_VCAP                 D0040PA01X+009150Y+142370               S0      
317ADM1276_VCAP     VIA        MD0040PA04X+009586Y+144836               S0      
317ADM1276_VCAP     VIA        MD0040PA00X+008900Y+142817               S0      
317ADM1276_VCAP     VIA        MD0040PA00X+008720Y+144000               S0      
317ADM1276_VCAP     VIA        MD0040PA00X+009980Y+145560               S0      
327P3V3_IN                      D0040PA01X+007740Y+097630               S0      
327P3V3_IN                      D0040PA01X+006380Y+097560               S0      
317P3V3_IN                      D0040PA01X+005710Y+097490               S0      
317P3V3_IN                      D0040PA01X+007080Y+097580               S0      
317P3V3_IN          VIA        MD0040PA01X+005150Y+097410               S0      
327P3V3_BS_NET                  D0040PA01X+008800Y+097255               S0      
317P3V3_BS_NET                  D0040PA01X+008190Y+096620               S0      
317P3V3_BS_NET      VIA        MD0040PA01X+008760Y+096590               S0      
327P3V3_LX                      D0040PA01X+007740Y+097255               S0      
317P3V3_LX                      D0040PA01X+007830Y+096620               S0      
327P3V3_LX                      D0040PA01X+006390Y+094960               S0      
317P3V3_LX          VIA        MD0040PA01X+006000Y+096680               S0      
317P3V3_LX          VIA        MD0040PA01X+006690Y+096910               S0      
317P3V3_LX          VIA        MD0040PA01X+007300Y+096600               S0      
327P3V3_LX_COPPER               D0040PA01X+010450Y+093948               S0      
327P3V3_LX_COPPER               D0040PA01X+009600Y+094200               S0      
317P3V3_LX_COPPER               D0040PA01X+009400Y+095720               S0      
317P3V3_LX_COPPER               D0040PA01X+010350Y+097420               S0      
327P3V3_LX_COPPER               D0040PA01X+008670Y+094960               S0      
317P3V3_LX_COPPER   VIA        MD0040PA01X+010350Y+096650               S0      
317P3V3_LX_COPPER   VIA        MD0040PA01X+009450Y+095050               S0      
327P3V3_FB                      D0040PA01X+008800Y+098005               S0      
317P3V3_FB                      D0040PA01X+010350Y+097980               S0      
317P3V3_FB                      D0040PA01X+009450Y+098230               S0      
317P3V3_FB                      D0040PA01X+009900Y+097970               S0      
317P3V3_FB          VIA        MD0040PA01X+009054Y+098796               S0      
327ADM1276_TIMER                D0040PA01X+010740Y+144688               S0      
317ADM1276_TIMER                D0040PA01X+009480Y+143150               S0      
317ADM1276_TIMER    VIA        MD0040PA01X+010020Y+143380               S0      
317NNAME00029                   D0040PA01X+013220Y+148200               S0      
317NNAME00029                   D0040PA01X+013350Y+147680               S0      
317NNAME00029       VIA        MD0040PA01X+013650Y+148143               S0      
327NNAME00030                   D0040PA01X+017000Y+159007               S0      
327NNAME00030                   D0040PA01X+018370Y+160650               S0      
327NNAME00030                   D0040PA01X+015775Y+161330               S0      
327NNAME00030                   D0040PA01X+006790Y+159017               S0      
327NNAME00030                   D0040PA01X+010175Y+161330               S0      
327NNAME00030                   D0040PA01X+013025Y+161330               S0      
327NNAME00030                   D0040PA01X+010100Y+159007               S0      
327NNAME00030                   D0040PA01X+007125Y+161330               S0      
327NNAME00030                   D0040PA01X+013600Y+159007               S0      
317NNAME00030       VIA        MD0040PA01X+012050Y+160600               S0      
317NNAME00030       VIA        MD0040PA01X+005330Y+160920               S0      
317NNAME00030       VIA        MD0040PA01X+006440Y+160590               S0      
317NNAME00030       VIA        MD0040PA01X+008950Y+161000               S0      
317NNAME00030       VIA        MD0040PA00X+010400Y+160550               S0      
317NNAME00030       VIA        MD0040PA00X+011350Y+160550               S0      
317NNAME00030       VIA        MD0040PA00X+011600Y+158400               S0      
317NNAME00030       VIA        MD0040PA00X+011600Y+159200               S0      
317NNAME00030       VIA        MD0040PA00X+011600Y+160000               S0      
317NNAME00030       VIA        MD0040PA00X+011600Y+161200               S0      
317NNAME00030       VIA        MD0040PA00X+012200Y+158400               S0      
317NNAME00030       VIA        MD0040PA00X+012200Y+159200               S0      
317NNAME00030       VIA        MD0040PA00X+012200Y+160000               S0      
317NNAME00030       VIA        MD0040PA00X+012200Y+161200               S0      
317NNAME00030       VIA        MD0040PA00X+012800Y+160600               S0      
317NNAME00030       VIA        MD0040PA00X+013850Y+160600               S0      
317NNAME00030       VIA        MD0040PA00X+014600Y+161200               S0      
317NNAME00030       VIA        MD0040PA00X+014800Y+160600               S0      
317NNAME00030       VIA        MD0040PA00X+015050Y+158200               S0      
317NNAME00030       VIA        MD0040PA00X+015050Y+159100               S0      
317NNAME00030       VIA        MD0040PA00X+015050Y+160000               S0      
317NNAME00030       VIA        MD0040PA00X+015600Y+158200               S0      
317NNAME00030       VIA        MD0040PA00X+015600Y+160600               S0      
317NNAME00030       VIA        MD0040PA00X+015650Y+159100               S0      
317NNAME00030       VIA        MD0040PA00X+015650Y+160000               S0      
317NNAME00030       VIA        MD0040PA00X+016400Y+160600               S0      
317NNAME00030       VIA        MD0040PA00X+017200Y+160600               S0      
317NNAME00030       VIA        MD0040PA00X+018250Y+158450               S0      
317NNAME00030       VIA        MD0040PA00X+018250Y+159200               S0      
317NNAME00030       VIA        MD0040PA00X+018250Y+159940               S0      
317NNAME00030       VIA        MD0040PA00X+005060Y+158280               S0      
317NNAME00030       VIA        MD0040PA00X+005060Y+158930               S0      
317NNAME00030       VIA        MD0040PA00X+005060Y+159530               S0      
317NNAME00030       VIA        MD0040PA00X+005060Y+160130               S0      
317NNAME00030       VIA        MD0040PA00X+005530Y+158260               S0      
317NNAME00030       VIA        MD0040PA00X+005530Y+158910               S0      
317NNAME00030       VIA        MD0040PA00X+005530Y+159510               S0      
317NNAME00030       VIA        MD0040PA00X+005530Y+160110               S0      
317NNAME00030       VIA        MD0040PA00X+005540Y+161330               S0      
317NNAME00030       VIA        MD0040PA00X+005850Y+160770               S0      
317NNAME00030       VIA        MD0040PA00X+006870Y+160390               S0      
317NNAME00030       VIA        MD0040PA00X+007160Y+160770               S0      
317NNAME00030       VIA        MD0040PA00X+009450Y+160550               S0      
317P12VU_2490_RC                D0040PA01X+009870Y+054960               S0      
317P12VU_2490_RC                D0040PA01X+009860Y+055330               S0      
317P12VU_2490_RC    VIA        MD0040PA01X+010180Y+055740               S0      
317P12VL_2490_RC                D0040PA01X+016340Y+054930               S0      
317P12VL_2490_RC                D0040PA01X+016330Y+054560               S0      
317P12VL_2490_RC    VIA        MD0040PA01X+016420Y+054190               S0      
327NNAME00031                   D0040PA01X+008737Y+054475               S0      
317NNAME00031                   D0040PA01X+008140Y+053390               S0      
317NNAME00031                   D0040PA01X+008680Y+053780               S0      
317NNAME00031                   D0040PA01X+008593Y+053368               S0      
317NNAME00031       VIA        MD0040PA01X+007740Y+053630               S0      
327P12VU_2490_VCC               D0040PA01X+008934Y+054475               S0      
317P12VU_2490_VCC               D0040PA01X+009610Y+053780               S0      
317P12VU_2490_VCC               D0040PA01X+009610Y+053390               S0      
317P12VU_2490_VCC               D0040PA01X+009040Y+053780               S0      
317P12VU_2490_VCC               D0040PA01X+009153Y+053368               S0      
317P12VU_2490_VCC   VIA        MD0040PA01X+009690Y+054160               S0      
317NNAME00032                   D0040PA01X+016090Y+053650               S0      
327NNAME00032                   D0040PA01X+015117Y+054295               S0      
317NNAME00032                   D0040PA01X+016030Y+053210               S0      
317NNAME00032                   D0040PA01X+015560Y+053240               S0      
317NNAME00032       VIA        MD0040PA01X+015150Y+053300               S0      
317P12VL_2490_VCC               D0040PA01X+016450Y+053650               S0      
327P12VL_2490_VCC               D0040PA01X+015314Y+054295               S0      
317P12VL_2490_VCC               D0040PA01X+016590Y+053210               S0      
317P12VL_2490_VCC               D0040PA01X+017060Y+053250               S0      
317P12VL_2490_VCC               D0040PA01X+017060Y+053640               S0      
317P12VL_2490_VCC   VIA        MD0040PA01X+017480Y+053220               S0      
317ADM1276_OV                   D0040PA01X+008350Y+146180               S0      
327ADM1276_OV                   D0040PA01X+008950Y+146170               S0      
327ADM1276_OV                   D0040PA01X+010740Y+145712               S0      
317ADM1276_OV                   D0040PA01X+009550Y+146080               S0      
317ADM1276_OV       VIA        MD0040PA01X+010100Y+146075               S0      
327NNAME00033                   D0040PA01X+008343Y+056105               S0      
317NNAME00033                   D0040PA01X+007410Y+057060               S0      
317NNAME00033       VIA        MD0040PA01X+007040Y+056550               S0      
317NNAME00034                   D0040PA01X+014040Y+056680               S0      
327NNAME00034                   D0040PA01X+014723Y+055925               S0      
317NNAME00034       VIA        MD0040PA01X+013520Y+056640               S0      
317NNAME00035                   D0040PA01X+008740Y+057410               S0      
327NNAME00035                   D0040PA01X+008737Y+056105               S0      
317NNAME00035                   D0040PA01X+008710Y+056990               S0      
317NNAME00035       VIA        MD0040PA01X+008362Y+058174               S0      
327NNAME00036                   D0040PA01X+015117Y+055925               S0      
317NNAME00036                   D0040PA01X+014870Y+056800               S0      
317NNAME00036                   D0040PA01X+014950Y+057860               S0      
317NNAME00036       VIA        MD0040PA01X+014950Y+057460               S0      
327NNAME00037                   D0040PA01X+014230Y+147180               S0      
317NNAME00037                   D0040PA01X+014850Y+147410               S0      
317NNAME00037       VIA        MD0040PA01X+014850Y+147950               S0      
327ADM1276_GATE                 D0040PA01X+014230Y+148080               S0      
317ADM1276_GATE                 D0040PA01X+014200Y+148780               S0      
317ADM1276_GATE                 D0040PA01X+012900Y+147685               S0      
317ADM1276_GATE                 D0040PA01X+014650Y+148780               S0      
317ADM1276_GATE                 D0040PA01X+012880Y+148200               S0      
317ADM1276_GATE                 D0040PA01X+013790Y+148770               S0      
317ADM1276_GATE                 D0040PA01X+015100Y+148780               S0      
317ADM1276_GATE     VIA        MD0040PA01X+013018Y+148668               S0      
317NNAME00038                   D0040PA01X+014200Y+149120               S0      
327NNAME00038                   D0040PA01X+010850Y+157550               S0      
317NNAME00038       VIA        MD0040PA04X+010850Y+155650               S0      
317NNAME00038       VIA        MD0040PA04X+013400Y+151950               S0      
317NNAME00038       VIA        MD0040PA00X+010850Y+156900               S0      
317NNAME00038       VIA        MD0040PA00X+014200Y+149480               S0      
327NNAME00039                   D0040PA01X+008400Y+044000               S0      
317NNAME00039                   D0040PA01X+007080Y+043130               S0      
317NNAME00039       VIA        MD0040PA01X+007090Y+042720               S0      
327P12VU_NET                    D0040PA01X+007200Y+047355               S0      
327P12VU_NET                    D0040PA01X+007650Y+045456               S0      
327P12VU_NET                    D0040PA01X+009000Y+047355               S0      
317P12VU_NET                    D0040PA01X+008140Y+053050               S0      
327P12VU_NET                    D0040PA01X+010400Y+045407               S0      
317P12VU_NET        VIA        MD0040PA01X+010650Y+046950               S0      
317P12VU_NET        VIA        MD0040PA01X+011550Y+047670               S0      
317P12VU_NET        VIA        MD0040PA00X+008770Y+052800               S0      
317P12VU_NET        VIA        MD0040PA00X+011150Y+047300               S0      
317P12VU_NET        VIA        MD0040PA00X+011700Y+044900               S0      
317P12VU_NET        VIA        MD0040PA00X+011700Y+045500               S0      
317P12VU_NET        VIA        MD0040PA00X+011700Y+046050               S0      
317P12VU_NET        VIA        MD0040PA00X+011700Y+046600               S0      
317P12VU_NET        VIA        MD0040PA00X+011700Y+047150               S0      
317P12VU_NET        VIA        MD0040PA00X+012150Y+047550               S0      
317P12VU_NET        VIA        MD0040PA00X+012250Y+045050               S0      
317P12VU_NET        VIA        MD0040PA00X+012250Y+045750               S0      
317P12VU_NET        VIA        MD0040PA00X+012250Y+046350               S0      
317P12VU_NET        VIA        MD0040PA00X+012250Y+046950               S0      
317P12VU_NET        VIA        MD0040PA00X+006250Y+047290               S0      
317P12VU_NET        VIA        MD0040PA00X+006250Y+047700               S0      
317P12VU_NET        VIA        MD0040PA00X+006260Y+046850               S0      
317P12VU_NET        VIA        MD0040PA00X+006330Y+046440               S0      
317P12VU_NET        VIA        MD0040PA00X+006400Y+044650               S0      
317P12VU_NET        VIA        MD0040PA00X+006400Y+045100               S0      
317P12VU_NET        VIA        MD0040PA00X+006400Y+045550               S0      
317P12VU_NET        VIA        MD0040PA00X+006400Y+046000               S0      
317P12VU_NET        VIA        MD0040PA00X+007820Y+048170               S0      
317P12VU_NET        VIA        MD0040PA00X+008980Y+044600               S0      
317P12VU_NET        VIA        MD0040PA00X+008980Y+045290               S0      
317P12VU_NET        VIA        MD0040PA00X+008980Y+045900               S0      
317P12VU_NET        VIA        MD0040PA00X+008980Y+046480               S0      
317P12VU_NET        VIA        MD0040PA00X+009950Y+047300               S0      
327NNAME00040                   D0040PA01X+018400Y+043950               S0      
317NNAME00040                   D0040PA01X+019080Y+043950               S0      
317NNAME00040       VIA        MD0040PA01X+018993Y+043580               S0      
327P12VL_NET                    D0040PA01X+015800Y+047305               S0      
327P12VL_NET                    D0040PA01X+017650Y+045407               S0      
317P12VL_NET                    D0040PA01X+015560Y+052900               S0      
327P12VL_NET                    D0040PA01X+017600Y+047305               S0      
327P12VL_NET                    D0040PA01X+014850Y+045407               S0      
317P12VL_NET        VIA        MD0040PA01X+014440Y+047080               S0      
317P12VL_NET        VIA        MD0040PA00X+016250Y+052790               S0      
317P12VL_NET        VIA        MD0040PA00X+016530Y+048110               S0      
317P12VL_NET        VIA        MD0040PA00X+013050Y+045400               S0      
317P12VL_NET        VIA        MD0040PA00X+013050Y+046100               S0      
317P12VL_NET        VIA        MD0040PA00X+013050Y+046800               S0      
317P12VL_NET        VIA        MD0040PA00X+013050Y+047450               S0      
317P12VL_NET        VIA        MD0040PA00X+013100Y+044700               S0      
317P12VL_NET        VIA        MD0040PA00X+013550Y+045400               S0      
317P12VL_NET        VIA        MD0040PA00X+013550Y+046100               S0      
317P12VL_NET        VIA        MD0040PA00X+013550Y+046800               S0      
317P12VL_NET        VIA        MD0040PA00X+013550Y+047450               S0      
317P12VL_NET        VIA        MD0040PA00X+013600Y+044700               S0      
317P12VL_NET        VIA        MD0040PA00X+016160Y+044590               S0      
317P12VL_NET        VIA        MD0040PA00X+016190Y+045160               S0      
317P12VL_NET        VIA        MD0040PA00X+016190Y+046330               S0      
317P12VL_NET        VIA        MD0040PA00X+016200Y+045760               S0      
317P12VL_NET        VIA        MD0040PA00X+018850Y+047450               S0      
317P12VL_NET        VIA        MD0040PA00X+018990Y+046050               S0      
317P12VL_NET        VIA        MD0040PA00X+018990Y+046750               S0      
317P12VL_NET        VIA        MD0040PA00X+019024Y+044745               S0      
317P12VL_NET        VIA        MD0040PA00X+019040Y+045350               S0      
317P12VL_NET        VIA        MD0040PA00X+019450Y+047450               S0      
317P12VL_NET        VIA        MD0040PA00X+019500Y+046050               S0      
317P12VL_NET        VIA        MD0040PA00X+019500Y+046750               S0      
317P12VL_NET        VIA        MD0040PA00X+019550Y+045350               S0      
317P12VL_NET        VIA        MD0040PA00X+019560Y+044750               S0      
327NNAME00041                   D0040PA01X+007540Y+157560               S0      
317NNAME00041                   D0040PA01X+013790Y+149110               S0      
317NNAME00041       VIA        MD0040PA04X+008190Y+151020               S0      
317NNAME00041       VIA        MD0040PA00X+013230Y+149110               S0      
317NNAME00041       VIA        MD0040PA00X+006770Y+156870               S0      
317NNAME00042                   D0040PA01X+014650Y+149120               S0      
327NNAME00042                   D0040PA01X+014350Y+157550               S0      
317NNAME00042       VIA        MD0040PA04X+014352Y+154000               S0      
317NNAME00042       VIA        MD0040PA04X+014750Y+150500               S0      
317NNAME00042       VIA        MD0040PA00X+014352Y+156752               S0      
317NNAME00042       VIA        MD0040PA00X+014750Y+149800               S0      
327NNAME00043                   D0040PA01X+017750Y+157550               S0      
317NNAME00043                   D0040PA01X+015100Y+149120               S0      
317NNAME00043       VIA        MD0040PA04X+015700Y+152800               S0      
317NNAME00043       VIA        MD0040PA00X+015350Y+149650               S0      
317NNAME00043       VIA        MD0040PA00X+017750Y+156950               S0      
317ADM1276_EN_NET               D0040PA01X+013750Y+144370               S0      
317ADM1276_EN_NET               D0040PA01X+016070Y+145800               S0      
327ADM1276_EN_NET               D0040PA01X+016700Y+145770               S0      
317ADM1276_EN_NET               D0040PA01X+014363Y+144475               S0      
317ADM1276_EN_NET   VIA        MD0040PA01X+013800Y+144850               S0      
317ADM1276_LATCH#               D0040PA01X+010050Y+142370               S0      
317ADM1276_LATCH#               D0040PA01X+016540Y+143020               S0      
327ADM1276_LATCH#               D0040PA01X+011188Y+144240               S0      
317ADM1276_LATCH#               D0040PA01X+016083Y+143028               S0      
327ADM1276_LATCH#               D0040PA01X+016549Y+143747               S0      
317ADM1276_LATCH#               D0040PA01X+010500Y+142370               S0      
317ADM1276_LATCH#               D0040PA01X+010970Y+142590               S0      
317ADM1276_LATCH#   VIA        MD0040PA01X+010300Y+142950               S0      
317ADM1276_LATCH#   VIA        MD0040PA00X+011000Y+142950               S0      
317ADM1276_LATCH#   VIA        MD0040PA00X+013200Y+143650               S0      
317NNAME00044                   D0040PA01X+011790Y+043750               S0      
327NNAME00044                   D0040PA01X+011150Y+043950               S0      
317NNAME00044       VIA        MD0040PA01X+011850Y+044200               S0      
317NNAME00045                   D0040PA01X+015350Y+043080               S0      
327NNAME00045                   D0040PA01X+015600Y+043950               S0      
317NNAME00045       VIA        MD0040PA01X+016261Y+043817               S0      
317TEMP_ALM#_IN                 D0040PA01X+015450Y+068380               S0      
327TEMP_ALM#_IN                 D0040PA01X+014163Y+068225               S0      
317TEMP_ALM#_IN     VIA        MD0040PA01X+014550Y+067500               S0      
317NNAME00046                   D0040PA01X+012900Y+147415               S0      
327NNAME00046                   D0040PA01X+012212Y+146160               S0      
317NNAME00046       VIA        MD0040PA01X+012730Y+146880               S0      
327NNAME00047                   D0040PA01X+014920Y+054295               S0      
317NNAME00047                   D0040PA01X+015010Y+043080               S0      
317NNAME00047                   D0040PA01X+019420Y+043950               S0      
317NNAME00047                   D0040PA01X+015990Y+054560               S0      
317NNAME00047       VIA        MD0040PA04X+017930Y+053000               S0      
317NNAME00047       VIA        MD0040PA00X+014696Y+043240               S0      
317NNAME00047       VIA        MD0040PA00X+015985Y+054180               S0      
317NNAME00047       VIA        MD0040PA00X+019140Y+043241               S0      
327NNAME00048                   D0040PA01X+008540Y+054475               S0      
317NNAME00048                   D0040PA01X+007420Y+043130               S0      
317NNAME00048                   D0040PA01X+012130Y+043750               S0      
317NNAME00048                   D0040PA01X+010210Y+054960               S0      
317NNAME00048       VIA        MD0040PA04X+010530Y+052520               S0      
317NNAME00048       VIA        MD0040PA01X+009980Y+054560               S0      
317NNAME00048       VIA        MD0040PA00X+011040Y+055080               S0      
317NNAME00048       VIA        MD0040PA00X+012250Y+044100               S0      
317NNAME00048       VIA        MD0040PA00X+007800Y+042950               S0      
327P12VU_2490_PG                D0040PA01X+008146Y+054475               S0      
317P12VU_2490_PG                D0040PA01X+007370Y+054330               S0      
317P12VU_2490_PG                D0040PA01X+007390Y+055010               S0      
317P12VU_2490_PG                D0040PA01X+007390Y+055540               S0      
327P12VL_2490_PG                D0040PA01X+014527Y+054295               S0      
317P12VL_2490_PG                D0040PA01X+013678Y+054307               S0      
317P12VL_2490_PG                D0040PA01X+013677Y+054852               S0      
317P12VL_2490_PG                D0040PA01X+013668Y+055377               S0      
327ADM1276_ADR                  D0040PA01X+011444Y+144240               S0      
317ADM1276_ADR                  D0040PA01X+009560Y+142030               S0      
317ADM1276_ADR                  D0040PA01X+009150Y+142030               S0      
317ADM1276_ADR      VIA        MD0040PA04X+010160Y+143100               S0      
317ADM1276_ADR      VIA        MD0040PA00X+010950Y+143800               S0      
317ADM1276_ADR      VIA        MD0040PA00X+009850Y+142840               S0      
327NNAME00049                   D0040PA01X+008540Y+056105               S0      
317NNAME00049                   D0040PA01X+008370Y+056990               S0      
317NNAME00049                   D0040PA01X+007860Y+057110               S0      
317NNAME00049       VIA        MD0040PA01X+008290Y+057450               S0      
317NNAME00050                   D0040PA01X+014530Y+057880               S0      
327NNAME00050                   D0040PA01X+014920Y+055925               S0      
317NNAME00050                   D0040PA01X+014530Y+056800               S0      
317NNAME00050       VIA        MD0040PA01X+014523Y+057170               S0      
317ADM1276_EN                   D0040PA01X+013750Y+144030               S0      
327ADM1276_EN                   D0040PA01X+011700Y+144240               S0      
317ADM1276_EN                   D0040PA01X+012500Y+140945               S0      
317ADM1276_EN                   D0040PA01X+017520Y+070110               S0      
317ADM1276_EN                   D0040PA01X+011310Y+142160               S0      
317ADM1276_EN                   D0040PA01X+011310Y+142590               S0      
317ADM1276_EN       VIA        MD0040PA04X+012250Y+143751               S0      
317ADM1276_EN       VIA        MD0040PA00X+013117Y+141270               S0      
317ADM1276_EN       VIA        MD0040PA00X+015520Y+067950               S0      
317ADM1276_EN       VIA        MD0040PA00X+011700Y+143520               S0      
317ADM1276_EN       VIA        MD0040PA00X+013380Y+144070               S0      
317ADM1276_GPIO2                D0040PA01X+011710Y+143010               S0      
317ADM1276_GPIO2                D0040PA01X+011800Y+142420               S0      
327ADM1276_GPIO2                D0040PA01X+011956Y+144240               S0      
317ADM1276_SENSE+               D0040PA01X+010900Y+149830               S0      
317ADM1276_SENSE+               D0040PA01X+011700Y+149830               S0      
317ADM1276_SENSE+               D0040PA01X+011300Y+149830               S0      
327ADM1276_SENSE+               D0040PA01X+011700Y+146160               S0      
317ADM1276_SENSE+               D0040PA01X+012100Y+149830               S0      
317ADM1276_SENSE+   VIA        MD0040PA01X+010433Y+149817               S0      
317SENSE+_R4                    D0040PA01X+010900Y+150170               S0      
327SENSE+_R4                    D0040PA01X+016525Y+161970               S0      
317SENSE+_R4        VIA        MD0040PA04X+010450Y+150600               S0      
317SENSE+_R4        VIA        MD0040PA00X+010900Y+150650               S0      
317SENSE+_R4        VIA        MD0040PA00X+016988Y+162630               S0      
317SENSE+_R3                    D0040PA01X+011300Y+150170               S0      
327SENSE+_R3                    D0040PA01X+013775Y+161970               S0      
317SENSE+_R3        VIA        MD0040PA04X+010850Y+150150               S0      
317SENSE+_R3        VIA        MD0040PA00X+011300Y+150650               S0      
317SENSE+_R3        VIA        MD0040PA00X+014130Y+162500               S0      
317SENSE+_R2                    D0040PA01X+011700Y+150170               S0      
327SENSE+_R2                    D0040PA01X+010925Y+161970               S0      
317SENSE+_R2        VIA        MD0040PA04X+011450Y+150180               S0      
317SENSE+_R2        VIA        MD0040PA00X+011320Y+162280               S0      
317SENSE+_R2        VIA        MD0040PA00X+011700Y+150650               S0      
317SENSE+_R1                    D0040PA01X+012100Y+150170               S0      
327SENSE+_R1                    D0040PA01X+007875Y+161970               S0      
317SENSE+_R1        VIA        MD0040PA04X+011950Y+150100               S0      
317SENSE+_R1        VIA        MD0040PA00X+012100Y+150650               S0      
317SENSE+_R1        VIA        MD0040PA00X+008300Y+161970               S0      
317ADM1276_SENSE-               D0040PA01X+013700Y+149830               S0      
327ADM1276_SENSE-               D0040PA01X+011956Y+146160               S0      
317ADM1276_SENSE-               D0040PA01X+012500Y+149830               S0      
317ADM1276_SENSE-               D0040PA01X+012900Y+149830               S0      
317ADM1276_SENSE-               D0040PA01X+013300Y+149830               S0      
317ADM1276_SENSE-   VIA        MD0040PA01X+014240Y+149990               S0      
317SENSE-_R1                    D0040PA01X+012500Y+150170               S0      
327SENSE-_R1                    D0040PA01X+007875Y+161330               S0      
317SENSE-_R1        VIA        MD0040PA04X+012500Y+150050               S0      
317SENSE-_R1        VIA        MD0040PA00X+012500Y+150650               S0      
317SENSE-_R1        VIA        MD0040PA00X+008305Y+161600               S0      
327SENSE-_R2                    D0040PA01X+010925Y+161330               S0      
317SENSE-_R2                    D0040PA01X+012900Y+150170               S0      
317SENSE-_R2        VIA        MD0040PA04X+013000Y+150100               S0      
317SENSE-_R2        VIA        MD0040PA00X+011320Y+161930               S0      
317SENSE-_R2        VIA        MD0040PA00X+012900Y+150650               S0      
327SENSE-_R3                    D0040PA01X+013775Y+161330               S0      
317SENSE-_R3                    D0040PA01X+013300Y+150170               S0      
317SENSE-_R3        VIA        MD0040PA04X+013500Y+150050               S0      
317SENSE-_R3        VIA        MD0040PA00X+013300Y+150550               S0      
317SENSE-_R3        VIA        MD0040PA00X+014150Y+162160               S0      
317SENSE-_R4                    D0040PA01X+013700Y+150170               S0      
327SENSE-_R4                    D0040PA01X+016525Y+161330               S0      
317SENSE-_R4        VIA        MD0040PA04X+013850Y+150450               S0      
317SENSE-_R4        VIA        MD0040PA00X+013501Y+150825               S0      
317SENSE-_R4        VIA        MD0040PA00X+017327Y+162652               S0      
317ADM1276_PWRGD                D0040PA01X+014020Y+145330               S0      
327ADM1276_PWRGD                D0040PA01X+012660Y+144944               S0      
317ADM1276_PWRGD    VIA        MD0040PA01X+013300Y+144760               S0      
317TEMP_ALM#                    D0040PA01X+011530Y+140820               S0      
317TEMP_ALM#                    D0040PA01X+015450Y+068720               S0      
317TEMP_ALM#                    D0040PA01X+009247Y+060697               S0      
317TEMP_ALM#                    D0040PA01X+012934Y+066203               S0      
327TEMP_ALM#                    D0040PA01X+011380Y+139970               S0      
317TEMP_ALM#                    D0040PA01X+015573Y+061507               S0      
317TEMP_ALM#        VIA        MD0040PA04X+014600Y+064140               S0      
317TEMP_ALM#        VIA        MD0040PA00X+012870Y+140800               S0      
317TEMP_ALM#        VIA        MD0040PA00X+014265Y+066543               S0      
317TEMP_ALM#        VIA        MD0040PA00X+015098Y+068778               S0      
317TEMP_ALM#        VIA        MD0040PA00X+015270Y+061880               S0      
317TEMP_ALM#        VIA        MD0040PA00X+009063Y+060202               S0      
327D_LATCH_Q                    D0040PA01X+016606Y+071010               S0      
317D_LATCH_Q                    D0040PA01X+016770Y+069960               S0      
317D_LATCH_Q                    D0040PA01X+017180Y+070110               S0      
317D_LATCH_Q        VIA        MD0040PA01X+016760Y+070330               S0      
327P3V3_EN                      D0040PA01X+007740Y+098005               S0      
317P3V3_EN                      D0040PA01X+007660Y+098660               S0      
317P3V3_EN                      D0040PA01X+007080Y+098140               S0      
317P3V3_EN          VIA        MD0040PA01X+008150Y+098590               S0      
317P3V3_LX_REV                  D0040PA01X+009400Y+096280               S0      
317P3V3_LX_REV                  D0040PA01X+009900Y+097630               S0      
317P3V3_LX_REV      VIA        MD0040PA01X+009796Y+096696               S0      
317ADM1276_FLB                  D0040PA01X+014050Y+145840               S0      
317ADM1276_FLB                  D0040PA01X+014050Y+146240               S0      
327ADM1276_FLB                  D0040PA01X+012660Y+145200               S0      
317ADM1276_FLB      VIA        MD0040PA01X+013440Y+145430               S0      
327ADM1276_VOUT                 D0040PA01X+012660Y+145456               S0      
317ADM1276_VOUT                 D0040PA01X+014050Y+146640               S0      
317ADM1276_VOUT     VIA        MD0040PA01X+013610Y+146390               S0      
327NNAME00051                   D0040PA01X+012212Y+144240               S0      
317NNAME00051                   D0040PA01X+012300Y+142420               S0      
317NNAME00051       VIA        MD0040PA01X+012300Y+143130               S0      
317NNAME00052                   D0040PA01X+012750Y+142420               S0      
327NNAME00052                   D0040PA01X+012660Y+144688               S0      
317NNAME00052       VIA        MD0040PA01X+012698Y+143540               S0      
317TEMP_ALM#_G                  D0040PA01X+010410Y+140810               S0      
327TEMP_ALM#_G                  D0040PA01X+010640Y+139970               S0      
327TEMP_ALM#_G                  D0040PA01X+010640Y+139714               S0      
317TEMP_ALM#_G      VIA        MD0040PA01X+009950Y+140750               S0      
327LED_DR_LED5_B                D0040PA01X+002747Y+026255               S0      
317LED_DR_LED5_B                D0040PA01X+003268Y+026422               S0      
317LED_DR_LED5_B    VIA        MD0040PA01X+002790Y+026947               S0      
317LED_DR_LED4_B                D0040PA01X+001928Y+030728               S0      
327LED_DR_LED4_B                D0040PA01X+002493Y+030535               S0      
317LED_DR_LED4_B    VIA        MD0040PA01X+002001Y+030298               S0      
317LED_DR_LED3_B                D0040PA01X+006410Y+090940               S0      
327LED_DR_LED3_B                D0040PA01X+005869Y+090987               S0      
317LED_DR_LED3_B    VIA        MD0040PA01X+006410Y+090480               S0      
327LED_DR_LED2_B                D0040PA01X+003187Y+108921               S0      
317LED_DR_LED2_B                D0040PA01X+003800Y+109600               S0      
317LED_DR_LED2_B    VIA        MD0040PA01X+003720Y+109170               S0      
327LED_DR_LED1_B                D0040PA01X+003538Y+164905               S0      
317LED_DR_LED1_B                D0040PA01X+003290Y+166080               S0      
317LED_DR_LED1_B    VIA        MD0040PA01X+003290Y+165630               S0      
327LED_DR_LED0_B                D0040PA01X+002729Y+171487               S0      
317LED_DR_LED0_B                D0040PA01X+002180Y+172070               S0      
317LED_DR_LED0_B    VIA        MD0040PA01X+003300Y+171850               S0      
317NNAME00053                   D0040PA01X+014424Y+064993               S0      
327NNAME00053                   D0040PA01X+013624Y+064015               S0      
317NNAME00053       VIA        MD0040PA01X+014520Y+064460               S0      
317I2C_C_SDA                    D0040PA01X+014424Y+065333               S0      
317I2C_C_SDA                    D0040PA01X+012330Y+100130               S0      
317I2C_C_SDA                    D0040PA01X+013500Y+100320               S0      
317I2C_C_SDA                    D0040PA01X+005830Y+026330               S0      
317I2C_C_SDA                    D0040PA01X+012300Y+142080               S0      
317I2C_C_SDA        VIA        MD0040PA04X+005910Y+044109               S0      
317I2C_C_SDA        VIA        MD0040PA00X+013560Y+141620               S0      
317I2C_C_SDA        VIA        MD0040PA00X+006030Y+027570               S0      
317I2C_C_SDA        VIA        MD0040PA00X+014680Y+101890               S0      
317I2C_C_SDA        VIA        MD0040PA00X+015143Y+066174               S0      
317NNAME00054                   D0040PA01X+009727Y+059747               S0      
327NNAME00054                   D0040PA01X+010284Y+062047               S0      
317NNAME00054       VIA        MD0040PA01X+009958Y+060577               S0      
317FANIN_1                      D0040PA01X+002330Y+176960               S0      
317FANIN_1                      D0040PA01X+002800Y+176990               S0      
327FANIN_1                      D0040PA01X+013036Y+064603               S0      
317FANIN_1          VIA        MD0040PA04X+013750Y+068250               S0      
317FANIN_1          VIA        MD0040PA00X+013890Y+065010               S0      
317FANIN_1          VIA        MD0040PA00X+002500Y+176380               S0      
317FANIN_2                      D0040PA01X+005430Y+176470               S0      
317FANIN_2                      D0040PA01X+004940Y+176980               S0      
327FANIN_2                      D0040PA01X+012840Y+064603               S0      
317FANIN_2          VIA        MD0040PA04X+014180Y+067630               S0      
317FANIN_2          VIA        MD0040PA00X+013920Y+065390               S0      
317FANIN_2          VIA        MD0040PA00X+004530Y+177630               S0      
317FANIN_3                      D0040PA01X+006320Y+113395               S0      
317FANIN_3                      D0040PA01X+006320Y+113860               S0      
327FANIN_3                      D0040PA01X+010284Y+063228               S0      
317FANIN_3          VIA        MD0040PA04X+007900Y+067550               S0      
317FANIN_3          VIA        MD0040PA00X+006730Y+113349               S0      
317FANIN_3          VIA        MD0040PA00X+008090Y+066840               S0      
317FANIN_4                      D0040PA01X+008140Y+113775               S0      
327FANIN_4                      D0040PA01X+010284Y+063031               S0      
317FANIN_4                      D0040PA01X+007700Y+113790               S0      
317FANIN_4          VIA        MD0040PA04X+013211Y+067835               S0      
317FANIN_4          VIA        MD0040PA00X+013114Y+063955               S0      
317FANIN_4          VIA        MD0040PA00X+007829Y+114804               S0      
327NNAME00055                   D0040PA01X+013990Y+098170               S0      
317NNAME00055                   D0040PA01X+013500Y+099980               S0      
317NNAME00055       VIA        MD0040PA01X+013090Y+100340               S0      
317NNAME00056                   D0040PA01X+013910Y+099970               S0      
327NNAME00056                   D0040PA01X+014246Y+098170               S0      
317NNAME00056       VIA        MD0040PA01X+014310Y+100710               S0      
317I2C_C_SCL                    D0040PA01X+005430Y+026330               S0      
317I2C_C_SCL                    D0040PA01X+014843Y+065333               S0      
317I2C_C_SCL                    D0040PA01X+013910Y+100310               S0      
317I2C_C_SCL                    D0040PA01X+011930Y+100130               S0      
317I2C_C_SCL                    D0040PA01X+012750Y+142080               S0      
317I2C_C_SCL        VIA        MD0040PA04X+007617Y+055147               S0      
317I2C_C_SCL        VIA        MD0040PA00X+013450Y+142000               S0      
317I2C_C_SCL        VIA        MD0040PA00X+005750Y+026850               S0      
317I2C_C_SCL        VIA        MD0040PA00X+014390Y+102270               S0      
317I2C_C_SCL        VIA        MD0040PA00X+014899Y+065857               S0      
317NCT7904_ADR                  D0040PA01X+013354Y+065863               S0      
317NCT7904_ADR                  D0040PA01X+013777Y+065867               S0      
327NCT7904_ADR                  D0040PA01X+012643Y+064603               S0      
317NCT7904_ADR      VIA        MD0040PA01X+012900Y+065360               S0      
317NCT7904_RESET                D0040PA01X+009307Y+059747               S0      
327NCT7904_RESET                D0040PA01X+010284Y+062244               S0      
317NCT7904_RESET    VIA        MD0040PA01X+009455Y+060120               S0      
317NCT7904_VSEN7                D0040PA01X+012490Y+058860               S0      
327NCT7904_VSEN7                D0040PA01X+012052Y+061263               S0      
317NCT7904_VSEN7                D0040PA01X+012890Y+058860               S0      
317NCT7904_VSEN7    VIA        MD0040PA01X+012080Y+059870               S0      
317PWM_OUT_FAN6                 D0040PA01X+008740Y+084410               S0      
327PWM_OUT_FAN6                 D0040PA01X+010338Y+084630               S0      
317PWM_OUT_FAN6                 D0040PA01X+010290Y+083180               S0      
317PWM_OUT_FAN6     VIA        MD0040PA01X+010340Y+083830               S0      
317PWM_OUT_FAN5                 D0040PA01X+008740Y+084850               S0      
317PWM_OUT_FAN5                 D0040PA01X+011120Y+083180               S0      
327PWM_OUT_FAN5                 D0040PA01X+010850Y+084630               S0      
317PWM_OUT_FAN5     VIA        MD0040PA01X+009240Y+084890               S0      
317PWM_OUT_FAN4                 D0040PA01X+008740Y+085290               S0      
317PWM_OUT_FAN4                 D0040PA01X+011960Y+083180               S0      
327PWM_OUT_FAN4                 D0040PA01X+011362Y+084630               S0      
317PWM_OUT_FAN4     VIA        MD0040PA01X+011930Y+083700               S0      
317PWM_OUT_FAN3                 D0040PA01X+008740Y+085720               S0      
327PWM_OUT_FAN3                 D0040PA01X+011617Y+086850               S0      
317PWM_OUT_FAN3                 D0040PA01X+011930Y+088140               S0      
317PWM_OUT_FAN3     VIA        MD0040PA01X+009270Y+085810               S0      
327PWM_OUT_FAN2                 D0040PA01X+011106Y+086850               S0      
317PWM_OUT_FAN2                 D0040PA01X+011090Y+088140               S0      
317PWM_OUT_FAN2                 D0040PA01X+008740Y+086150               S0      
317PWM_OUT_FAN2     VIA        MD0040PA01X+011110Y+087670               S0      
317PWM_OUT_FAN1                 D0040PA01X+010260Y+088140               S0      
327PWM_OUT_FAN1                 D0040PA01X+010594Y+086850               S0      
317PWM_OUT_FAN1                 D0040PA01X+008740Y+086570               S0      
317PWM_OUT_FAN1     VIA        MD0040PA01X+009280Y+086530               S0      
317NNAME00057                   D0040PA01X+016610Y+062670               S0      
317NNAME00057                   D0040PA01X+016610Y+062270               S0      
317NNAME00057                   D0040PA01X+017020Y+062710               S0      
317NNAME00057                   D0040PA01X+017430Y+062430               S0      
317NNAME00057       VIA        MD0040PA01X+017902Y+062001               S0      
317NCT7904_VSEN6                D0040PA01X+012080Y+058860               S0      
317NCT7904_VSEN6                D0040PA01X+011680Y+058860               S0      
327NCT7904_VSEN6                D0040PA01X+011855Y+061263               S0      
317NCT7904_VSEN6    VIA        MD0040PA01X+011856Y+059285               S0      
317NCT7904D_PWM1                D0040PA01X+011630Y+066720               S0      
327NCT7904D_PWM1                D0040PA01X+012052Y+064603               S0      
317NCT7904D_PWM1    VIA        MD0040PA01X+012209Y+066591               S0      
317NNAME00058                   D0040PA01X+005690Y+028000               S0      
317NNAME00058                   D0040PA01X+011900Y+066020               S0      
317NNAME00058                   D0040PA01X+011630Y+067060               S0      
327NNAME00058                   D0040PA01X+010850Y+086850               S0      
327NNAME00058                   D0040PA01X+010338Y+086850               S0      
317NNAME00058                   D0040PA01X+011630Y+067060               S0      
317NNAME00058       VIA        MD0040PA04X+011522Y+076552               S0      
317NNAME00058       VIA        MD0040PA00X+010230Y+086344               S0      
317NNAME00058       VIA        MD0040PA00X+010716Y+086229               S0      
317NNAME00058       VIA        MD0040PA00X+011813Y+066340               S0      
317NNAME00058       VIA        MD0040PA00X+004580Y+027780               S0      
317NCT7904D_PWM2                D0040PA01X+011560Y+065680               S0      
327NCT7904D_PWM2                D0040PA01X+011658Y+064603               S0      
317NCT7904D_PWM2    VIA        MD0040PA01X+011930Y+065660               S0      
317NNAME00059                   D0040PA01X+003620Y+027230               S0      
317NNAME00059                   D0040PA01X+011560Y+066020               S0      
327NNAME00059                   D0040PA01X+011106Y+084630               S0      
327NNAME00059                   D0040PA01X+011362Y+086850               S0      
317NNAME00059                   D0040PA01X+011560Y+066020               S0      
317NNAME00059                   D0040PA01X+010830Y+066220               S0      
317NNAME00059       VIA        MD0040PA04X+011640Y+077940               S0      
317NNAME00059       VIA        MD0040PA00X+011150Y+085160               S0      
317NNAME00059       VIA        MD0040PA00X+011340Y+086220               S0      
317NNAME00059       VIA        MD0040PA00X+011400Y+066335               S0      
317NNAME00059       VIA        MD0040PA00X+004340Y+027230               S0      
317NCT7904D_PWM3                D0040PA01X+010490Y+065880               S0      
327NCT7904D_PWM3                D0040PA01X+011265Y+064603               S0      
317NCT7904D_PWM3    VIA        MD0040PA01X+011140Y+065850               S0      
327NNAME00060                   D0040PA01X+010082Y+084630               S0      
327NNAME00060                   D0040PA01X+010594Y+084630               S0      
317NNAME00060                   D0040PA01X+010490Y+066220               S0      
317NNAME00060                   D0040PA01X+009520Y+066230               S0      
317NNAME00060                   D0040PA01X+010490Y+066220               S0      
317NNAME00060       VIA        MD0040PA04X+011110Y+078820               S0      
317NNAME00060       VIA        MD0040PA00X+010030Y+084100               S0      
317NNAME00060       VIA        MD0040PA00X+010640Y+084070               S0      
317NNAME00060       VIA        MD0040PA00X+010901Y+066589               S0      
317PWM_OUT                      D0040PA01X+011290Y+067060               S0      
327PWM_OUT                      D0040PA01X+009321Y+068242               S0      
317PWM_OUT          VIA        MD0040PA01X+009870Y+087710               S0      
317PWM_OUT          VIA        MD0040PA00X+010020Y+066390               S0      
317PWM_OUT          VIA        MD0040PA00X+010150Y+087420               S0      
317PWM_OUT          VIA        MD0040PA00X+007240Y+082290               S0      
317PWM_OUT          VIA        MD0040PA00X+008660Y+068110               S0      
317PWM_OUT          VIA        MD0040PA00X+009890Y+082290               S0      
317THERMHOT#                    D0040PA01X+008340Y+068220               S0      
317THERMHOT#                    D0040PA01X+008410Y+068640               S0      
327THERMHOT#                    D0040PA01X+009321Y+068742               S0      
317THERMHOT#        VIA        MD0040PA01X+008600Y+068990               S0      
327THERMHOT#_R                  D0040PA01X+007200Y+068111               S0      
317THERMHOT#_R                  D0040PA01X+008000Y+068220               S0      
317THERMHOT#_R      VIA        MD0040PA04X+008048Y+068392               S0      
317THERMHOT#_R      VIA        MD0040PA00X+007610Y+068690               S0      
317THERMHOT#_R      VIA        MD0040PA00X+008385Y+067811               S0      
317NNAME00061                   D0040PA01X+014843Y+064993               S0      
327NNAME00061                   D0040PA01X+013624Y+063819               S0      
317NNAME00061       VIA        MD0040PA01X+015320Y+065320               S0      
317NCT7368S_SEL                 D0040PA01X+008194Y+069464               S0      
317NCT7368S_SEL                 D0040PA01X+008196Y+069047               S0      
327NCT7368S_SEL                 D0040PA01X+009321Y+069242               S0      
317NCT7368S_SEL     VIA        MD0040PA01X+008606Y+069520               S0      
327D_LATCH_CLR                  D0040PA01X+015583Y+071010               S0      
317D_LATCH_CLR                  D0040PA01X+014950Y+071170               S0      
317D_LATCH_CLR      VIA        MD0040PA01X+014500Y+071175               S0      
317FCB_EEPROM_A0                D0040PA01X+011050Y+093970               S0      
327FCB_EEPROM_A0                D0040PA01X+011396Y+096300               S0      
317FCB_EEPROM_A0                D0040PA01X+011253Y+095574               S0      
317FCB_EEPROM_A0    VIA        MD0040PA01X+010820Y+095350               S0      
317NCT7904_TMPALM               D0040PA01X+009247Y+061037               S0      
327NCT7904_TMPALM               D0040PA01X+010284Y+062637               S0      
317NCT7904_TMPALM   VIA        MD0040PA01X+009146Y+062314               S0      
327FCB_EEPROM_A1                D0040PA01X+011652Y+096300               S0      
317FCB_EEPROM_A1                D0040PA01X+011753Y+095574               S0      
317FCB_EEPROM_A1                D0040PA01X+011730Y+093970               S0      
317FCB_EEPROM_A1    VIA        MD0040PA01X+011298Y+094684               S0      
317FCB_EEPROM_A2                D0040PA01X+012253Y+095574               S0      
327FCB_EEPROM_A2                D0040PA01X+011908Y+096300               S0      
317FCB_EEPROM_A2                D0040PA01X+012167Y+093976               S0      
317FCB_EEPROM_A2    VIA        MD0040PA01X+012005Y+094560               S0      
327EEPROM_WP                    D0040PA01X+011652Y+098520               S0      
317EEPROM_WP                    D0040PA01X+011480Y+099790               S0      
317EEPROM_WP        VIA        MD0040PA01X+011040Y+099785               S0      
327NNAME00062                   D0040PA01X+011908Y+098520               S0      
317NNAME00062                   D0040PA01X+011930Y+099790               S0      
317NNAME00062       VIA        MD0040PA01X+011908Y+099290               S0      
327NNAME00063                   D0040PA01X+012164Y+098520               S0      
317NNAME00063                   D0040PA01X+012330Y+099790               S0      
317NNAME00063       VIA        MD0040PA01X+012770Y+099840               S0      
327LED_DRV_RST                  D0040PA01X+014502Y+098170               S0      
317LED_DRV_RST                  D0040PA01X+014200Y+099450               S0      
317LED_DRV_RST                  D0040PA01X+014380Y+099980               S0      
327NNAME00064                   D0040PA01X+006688Y+067461               S0      
327NNAME00064                   D0040PA01X+004275Y+068544               S0      
317NNAME00064                   D0040PA01X+005740Y+067340               S0      
317NNAME00064       VIA        MD0040PA01X+005720Y+066788               S0      
317NCT7904_CLKIN                D0040PA01X+015134Y+063243               S0      
327NCT7904_CLKIN                D0040PA01X+013624Y+063622               S0      
317NCT7904_CLKIN    VIA        MD0040PA01X+014666Y+063405               S0      
317NCT7904_VSEN1                D0040PA01X+016270Y+062270               S0      
327NCT7904_VSEN1                D0040PA01X+013624Y+063031               S0      
317NCT7904_VSEN1    VIA        MD0040PA01X+015720Y+062080               S0      
317NCT7904_VSEN9                D0040PA01X+017020Y+062370               S0      
327NCT7904_VSEN9                D0040PA01X+012446Y+061263               S0      
317NCT7904_VSEN9    VIA        MD0040PA04X+013650Y+059700               S0      
317NCT7904_VSEN9    VIA        MD0040PA00X+012900Y+059700               S0      
317NCT7904_VSEN9    VIA        MD0040PA00X+017035Y+061995               S0      
327NNAME00065                   D0040PA01X+006943Y+067461               S0      
317NNAME00065                   D0040PA01X+006140Y+067340               S0      
327NNAME00065                   D0040PA01X+005825Y+068544               S0      
317NNAME00065       VIA        MD0040PA04X+006050Y+067470               S0      
317NNAME00065       VIA        MD0040PA00X+006050Y+068254               S0      
317NNAME00065       VIA        MD0040PA00X+006090Y+067020               S0      
317LED_DRV_A0                   D0040PA01X+013150Y+094780               S0      
327LED_DRV_A0                   D0040PA01X+013734Y+095950               S0      
317LED_DRV_A0       VIA        MD0040PA01X+013090Y+095818               S0      
327LED_DRV_A1                   D0040PA01X+013990Y+095950               S0      
317LED_DRV_A1                   D0040PA01X+013600Y+094780               S0      
317LED_DRV_A1       VIA        MD0040PA01X+013350Y+095300               S0      
327LED_DRV_A2                   D0040PA01X+014246Y+095950               S0      
317LED_DRV_A2                   D0040PA01X+014050Y+094780               S0      
317LED_DRV_A2       VIA        MD0040PA01X+013950Y+095150               S0      
317NNAME00066                   D0040PA01X+015210Y+099980               S0      
327NNAME00066                   D0040PA01X+015014Y+098170               S0      
317NNAME00066                   D0040PA01X+015400Y+099450               S0      
327NNAME00067                   D0040PA01X+014758Y+098170               S0      
317NNAME00067                   D0040PA01X+014790Y+099970               S0      
317NNAME00067                   D0040PA01X+014760Y+099460               S0      
317NCT7904_SMI                  D0040PA01X+015233Y+061507               S0      
327NCT7904_SMI                  D0040PA01X+013624Y+062637               S0      
317NCT7904_SMI      VIA        MD0040PA01X+014860Y+061830               S0      
317NCT7904_RSTOUT               D0040PA01X+012934Y+065863               S0      
327NCT7904_RSTOUT               D0040PA01X+012446Y+064603               S0      
317NCT7904_RSTOUT   VIA        MD0040PA01X+012520Y+065750               S0      
317FANIN_10                     D0040PA01X+004960Y+057690               S0      
327FANIN_10                     D0040PA01X+011067Y+064603               S0      
317FANIN_10                     D0040PA01X+004510Y+057730               S0      
317FANIN_10         VIA        MD0040PA04X+010640Y+064830               S0      
317FANIN_10         VIA        MD0040PA00X+010820Y+065583               S0      
317FANIN_10         VIA        MD0040PA00X+005680Y+057695               S0      
317FANIN_12                     D0040PA01X+008130Y+007150               S0      
317FANIN_12                     D0040PA01X+008580Y+007150               S0      
327FANIN_12                     D0040PA01X+011855Y+064603               S0      
317FANIN_12         VIA        MD0040PA04X+005875Y+010115               S0      
317FANIN_12         VIA        MD0040PA00X+011740Y+065310               S0      
317FANIN_12         VIA        MD0040PA00X+008150Y+007550               S0      
317FANIN_9                      D0040PA01X+007840Y+059100               S0      
317FANIN_9                      D0040PA01X+007350Y+059100               S0      
327FANIN_9                      D0040PA01X+011462Y+064603               S0      
317FANIN_9          VIA        MD0040PA04X+008290Y+062060               S0      
317FANIN_9          VIA        MD0040PA00X+011280Y+065350               S0      
317FANIN_9          VIA        MD0040PA00X+007250Y+059590               S0      
317FANIN_11                     D0040PA01X+008830Y+006150               S0      
317FANIN_11                     D0040PA01X+008385Y+006140               S0      
327FANIN_11                     D0040PA01X+012249Y+064603               S0      
317FANIN_11         VIA        MD0040PA04X+007840Y+008610               S0      
317FANIN_11         VIA        MD0040PA00X+012250Y+065365               S0      
317FANIN_11         VIA        MD0040PA00X+008825Y+006550               S0      
327NCT7904_GND                  D0040PA01X+010284Y+062834               S0      
327NCT7904_GND                  D0040PA01X+008944Y+063503               S0      
317NCT7904_GND      VIA        MD0040PA01X+009306Y+062913               S0      
317FANIN_6                      D0040PA01X+006200Y+102500               S0      
317FANIN_6                      D0040PA01X+006300Y+102060               S0      
327FANIN_6                      D0040PA01X+010284Y+063425               S0      
317FANIN_6          VIA        MD0040PA04X+006700Y+090730               S0      
317FANIN_6          VIA        MD0040PA00X+005350Y+102550               S0      
317FANIN_6          VIA        MD0040PA00X+008450Y+066635               S0      
317FANIN_8                      D0040PA01X+008150Y+072760               S0      
317FANIN_8                      D0040PA01X+007700Y+072740               S0      
327FANIN_8                      D0040PA01X+010284Y+063819               S0      
317FANIN_8          VIA        MD0040PA04X+008390Y+065975               S0      
317FANIN_8          VIA        MD0040PA00X+007300Y+072800               S0      
317FANIN_8          VIA        MD0040PA00X+008897Y+065975               S0      
317FANIN_5                      D0040PA01X+006870Y+099980               S0      
327FANIN_5                      D0040PA01X+010284Y+063622               S0      
317FANIN_5                      D0040PA01X+006420Y+099850               S0      
317FANIN_5          VIA        MD0040PA04X+005420Y+092670               S0      
317FANIN_5          VIA        MD0040PA00X+005400Y+099650               S0      
317FANIN_5          VIA        MD0040PA00X+008644Y+066285               S0      
317FANIN_7                      D0040PA01X+007720Y+070250               S0      
317FANIN_7                      D0040PA01X+008200Y+070260               S0      
327FANIN_7                      D0040PA01X+010284Y+064015               S0      
317FANIN_7          VIA        MD0040PA04X+008400Y+067400               S0      
317FANIN_7          VIA        MD0040PA00X+007557Y+069250               S0      
317FANIN_7          VIA        MD0040PA00X+009067Y+066337               S0      
317NCT7904_VSEN11               D0040PA01X+013194Y+060193               S0      
327NCT7904_VSEN11               D0040PA01X+012840Y+061263               S0      
317NCT7904_VSEN12               D0040PA01X+014014Y+059323               S0      
327NCT7904_VSEN12               D0040PA01X+013036Y+061263               S0      
317NCT7904_PECI                 D0040PA01X+015670Y+062680               S0      
327NCT7904_PECI                 D0040PA01X+013624Y+063228               S0      
317NCT7904_VSEN13               D0040PA01X+013993Y+060417               S0      
327NCT7904_VSEN13               D0040PA01X+013624Y+061850               S0      
317NCT7904_VSEN14               D0040PA01X+014433Y+059876               S0      
327NCT7904_VSEN14               D0040PA01X+013624Y+062047               S0      
317NNAME00068                   D0040PA01X+015103Y+062757               S0      
327NNAME00068                   D0040PA01X+013624Y+063425               S0      
317NCT7904_LED                  D0040PA01X+009297Y+061734               S0      
327NCT7904_LED                  D0040PA01X+010284Y+062441               S0      
327NNAME00069                   D0040PA01X+013624Y+062834               S0      
317NNAME00069                   D0040PA01X+016070Y+061590               S0      
327D_LATCH_Q#                   D0040PA01X+016862Y+071010               S0      
317D_LATCH_Q#                   D0040PA01X+017900Y+070650               S0      
327NCT7904D_PWM4                D0040PA01X+010871Y+064603               S0      
317NCT7904D_PWM4                D0040PA01X+010190Y+065410               S0      
317NCT7904_VSEN8                D0040PA01X+012583Y+059363               S0      
327NCT7904_VSEN8                D0040PA01X+012249Y+061263               S0      
317NCT7904_VSEN10               D0040PA01X+013274Y+059343               S0      
327NCT7904_VSEN10               D0040PA01X+012643Y+061263               S0      
999
